FILE_TYPE = MACRO_DRAWING;
SET COLOR_WIRE YELLOW;
SET COLOR_PROP ORANGE;
SET COLOR_DOT WHITE;
SET COLOR_ARC YELLOW;
SET COLOR_BODY GREEN;
SET COLOR_NOTE PURPLE;
SET PROP_DISPLAY VALUE;
SET PAGE_NUMBER P393;
FORCEADD OFFPAGE..1
(-4300 2175);
FORCEPROP 2 LAST $XR0 331 
J 0
(-4552 2175);
DISPLAY 0.638298 (-4552 2175);
PAINT MONO (-4552 2175);
FORCEPROP 2 LAST CDS_LIB standard
J 0
(-4300 2175);
DISPLAY INVISIBLE (-4300 2175);
FORCEPROP 1 LAST OFFPAGE TRUE
J 0
(-3975 2050);
DISPLAY 0.872340 (-3975 2050);
DISPLAY INVISIBLE (-3975 2050);
FORCEPROP 1 LAST COMMENT_BODY TRUE
J 0
(-4175 2075);
DISPLAY 0.872340 (-4175 2075);
PAINT GREEN (-4175 2075);
DISPLAY INVISIBLE (-4175 2075);
FORCEPROP 2 LAST PATH I1
J 0
(-4550 2225);
DISPLAY 0.680851 (-4550 2225);
DISPLAY INVISIBLE (-4550 2225);
FORCEADD TAP..1
R 2
(-3350 1750);
FORCEPROP 3 LASTPIN (-3300 1750) SIG_NAME P5E_CPU1_P1_TX_BUF_DN<2>
J 0
(-3290 1760);
DISPLAY 0.659574 (-3290 1760);
PAINT MONO (-3290 1760);
DISPLAY INVISIBLE (-3290 1760);
FORCEPROP 1 LASTPIN (-3300 1750) BN 2
J 2
(-3288 1758);
DISPLAY 0.680851 (-3288 1758);
PAINT GREEN (-3288 1758);
FORCEPROP 2 LAST CDS_LIB standard
J 0
(-3350 1750);
DISPLAY INVISIBLE (-3350 1750);
FORCEPROP 1 LAST BODY_TYPE PLUMBING
J 2
(-3350 1800);
DISPLAY 0.872340 (-3350 1800);
PAINT GREEN (-3350 1800);
DISPLAY INVISIBLE (-3350 1800);
FORCEPROP 1 LAST HDL_TAP TRUE
J 2
(-3675 1625);
DISPLAY 0.872340 (-3675 1625);
DISPLAY INVISIBLE (-3675 1625);
FORCEPROP 1 LAST PATH I10
J 2
(-3348 1750);
DISPLAY 0.872340 (-3348 1750);
PAINT GREEN (-3348 1750);
DISPLAY INVISIBLE (-3348 1750);
FORCEADD Q_CAP_DIFFBUS..2
R 2
(-7000 1750);
FORCEPROP 1 LAST LOCATION C6682
J 2
(-6725 1750);
DISPLAY 0.723404 (-6725 1750);
PAINT GREEN (-6725 1750);
FORCEPROP 2 LAST $SEC 1
J 2
(-6825 1825);
DISPLAY 0.680851 (-6825 1825);
PAINT MONO (-6825 1825);
DISPLAY INVISIBLE (-6825 1825);
FORCEPROP 2 LAST CDS_SEC 1
J 2
(-6825 1825);
DISPLAY 0.680851 (-6825 1825);
DISPLAY INVISIBLE (-6825 1825);
FORCEPROP 2 LASTPIN (-6925 1750) $PN 1
J 0
(-6915 1760);
DISPLAY 0.808511 (-6915 1760);
FORCEPROP 2 LASTPIN (-7075 1750) $PN 2
J 2
(-7085 1760);
DISPLAY 0.808511 (-7085 1760);
FORCEPROP 2 LAST VALUE DIFF BUS_0.22UF
J 2
(-7150 1750);
DISPLAY 0.553191 (-7150 1750);
FORCEPROP 2 LAST TOLERANCE 20%
J 2
(-7075 1800);
DISPLAY 0.553191 (-7075 1800);
DISPLAY INVISIBLE (-7075 1800);
FORCEPROP 2 LAST PACK_TYPE C0201
J 2
(-7175 1800);
DISPLAY 0.553191 (-7175 1800);
DISPLAY INVISIBLE (-7175 1800);
FORCEPROP 1 LAST MATERIAL X6S
J 2
(-6991 1829);
DISPLAY 0.574468 (-6991 1829);
PAINT GREEN (-6991 1829);
DISPLAY INVISIBLE (-6991 1829);
FORCEPROP 2 LAST VOLTAGE 6.3V
J 2
(-7350 1800);
DISPLAY 0.553191 (-7350 1800);
DISPLAY INVISIBLE (-7350 1800);
FORCEPROP 1 LAST PIN_NAMES_ROTATE TRUE
J 2
(-7000 1750);
DISPLAY 0.489362 (-7000 1750);
PAINT GREEN (-7000 1750);
DISPLAY INVISIBLE (-7000 1750);
FORCEPROP 2 LAST CDS_LIB pure_quanta
J 2
(-7000 1750);
DISPLAY INVISIBLE (-7000 1750);
FORCEPROP 1 LAST CDS_LMAN_SYM_OUTLINE -25,50,25,-50
J 2
(-7000 1750);
DISPLAY 0.468085 (-7000 1750);
PAINT GREEN (-7000 1750);
DISPLAY INVISIBLE (-7000 1750);
FORCEPROP 1 LAST PATH I100
J 2
(-7000 1750);
DISPLAY 0.723404 (-7000 1750);
DISPLAY INVISIBLE (-7000 1750);
FORCEPROP 1 LAST PART_NUMBER SP_CH4221MEE01
J 2
(-7116 1838);
DISPLAY 0.574468 (-7116 1838);
PAINT GREEN (-7116 1838);
DISPLAY INVISIBLE (-7116 1838);
FORCEPROP 1 LAST LOCATION C6682
J 0
(-6750 1825);
DISPLAY 1.021277 (-6750 1825);
DISPLAY INVISIBLE (-6750 1825);
FORCEADD Q_CAP_DIFFBUS..2
R 2
(-7000 2000);
FORCEPROP 1 LAST LOCATION C6679
J 2
(-6725 2000);
DISPLAY 0.723404 (-6725 2000);
PAINT GREEN (-6725 2000);
FORCEPROP 2 LAST $SEC 1
J 2
(-6825 2075);
DISPLAY 0.680851 (-6825 2075);
PAINT MONO (-6825 2075);
DISPLAY INVISIBLE (-6825 2075);
FORCEPROP 2 LAST CDS_SEC 1
J 2
(-6825 2075);
DISPLAY 0.680851 (-6825 2075);
DISPLAY INVISIBLE (-6825 2075);
FORCEPROP 2 LASTPIN (-6925 2000) $PN 1
J 0
(-6915 2010);
DISPLAY 0.808511 (-6915 2010);
FORCEPROP 2 LASTPIN (-7075 2000) $PN 2
J 2
(-7085 2010);
DISPLAY 0.808511 (-7085 2010);
FORCEPROP 2 LAST VALUE DIFF BUS_0.22UF
J 2
(-7150 2000);
DISPLAY 0.553191 (-7150 2000);
FORCEPROP 2 LAST TOLERANCE 20%
J 2
(-7075 2050);
DISPLAY 0.553191 (-7075 2050);
DISPLAY INVISIBLE (-7075 2050);
FORCEPROP 2 LAST PACK_TYPE C0201
J 2
(-7175 2050);
DISPLAY 0.553191 (-7175 2050);
DISPLAY INVISIBLE (-7175 2050);
FORCEPROP 1 LAST MATERIAL X6S
J 2
(-6991 2079);
DISPLAY 0.574468 (-6991 2079);
PAINT GREEN (-6991 2079);
DISPLAY INVISIBLE (-6991 2079);
FORCEPROP 2 LAST VOLTAGE 6.3V
J 2
(-7350 2050);
DISPLAY 0.553191 (-7350 2050);
DISPLAY INVISIBLE (-7350 2050);
FORCEPROP 1 LAST PIN_NAMES_ROTATE TRUE
J 2
(-7000 2000);
DISPLAY 0.489362 (-7000 2000);
PAINT GREEN (-7000 2000);
DISPLAY INVISIBLE (-7000 2000);
FORCEPROP 2 LAST CDS_LIB pure_quanta
J 2
(-7000 2000);
DISPLAY INVISIBLE (-7000 2000);
FORCEPROP 1 LAST CDS_LMAN_SYM_OUTLINE -25,50,25,-50
J 2
(-7000 2000);
DISPLAY 0.468085 (-7000 2000);
PAINT GREEN (-7000 2000);
DISPLAY INVISIBLE (-7000 2000);
FORCEPROP 1 LAST PATH I101
J 2
(-7000 2000);
DISPLAY 0.723404 (-7000 2000);
DISPLAY INVISIBLE (-7000 2000);
FORCEPROP 1 LAST PART_NUMBER SP_CH4221MEE01
J 2
(-7116 2088);
DISPLAY 0.574468 (-7116 2088);
PAINT GREEN (-7116 2088);
DISPLAY INVISIBLE (-7116 2088);
FORCEPROP 1 LAST LOCATION C6679
J 0
(-6750 2075);
DISPLAY 1.021277 (-6750 2075);
DISPLAY INVISIBLE (-6750 2075);
FORCEADD Q_CAP_DIFFBUS..2
R 2
(-7000 1950);
FORCEPROP 1 LAST LOCATION C6680
J 2
(-6725 1950);
DISPLAY 0.723404 (-6725 1950);
PAINT GREEN (-6725 1950);
FORCEPROP 2 LAST $SEC 1
J 2
(-6825 2025);
DISPLAY 0.680851 (-6825 2025);
PAINT MONO (-6825 2025);
DISPLAY INVISIBLE (-6825 2025);
FORCEPROP 2 LAST CDS_SEC 1
J 2
(-6825 2025);
DISPLAY 0.680851 (-6825 2025);
DISPLAY INVISIBLE (-6825 2025);
FORCEPROP 2 LASTPIN (-6925 1950) $PN 1
J 0
(-6915 1960);
DISPLAY 0.808511 (-6915 1960);
FORCEPROP 2 LASTPIN (-7075 1950) $PN 2
J 2
(-7085 1960);
DISPLAY 0.808511 (-7085 1960);
FORCEPROP 2 LAST VALUE DIFF BUS_0.22UF
J 2
(-7150 1950);
DISPLAY 0.553191 (-7150 1950);
FORCEPROP 2 LAST TOLERANCE 20%
J 2
(-7075 2000);
DISPLAY 0.553191 (-7075 2000);
DISPLAY INVISIBLE (-7075 2000);
FORCEPROP 2 LAST PACK_TYPE C0201
J 2
(-7175 2000);
DISPLAY 0.553191 (-7175 2000);
DISPLAY INVISIBLE (-7175 2000);
FORCEPROP 1 LAST MATERIAL X6S
J 2
(-6991 2029);
DISPLAY 0.574468 (-6991 2029);
PAINT GREEN (-6991 2029);
DISPLAY INVISIBLE (-6991 2029);
FORCEPROP 2 LAST VOLTAGE 6.3V
J 2
(-7350 2000);
DISPLAY 0.553191 (-7350 2000);
DISPLAY INVISIBLE (-7350 2000);
FORCEPROP 1 LAST PIN_NAMES_ROTATE TRUE
J 2
(-7000 1950);
DISPLAY 0.489362 (-7000 1950);
PAINT GREEN (-7000 1950);
DISPLAY INVISIBLE (-7000 1950);
FORCEPROP 2 LAST CDS_LIB pure_quanta
J 2
(-7000 1950);
DISPLAY INVISIBLE (-7000 1950);
FORCEPROP 1 LAST CDS_LMAN_SYM_OUTLINE -25,50,25,-50
J 2
(-7000 1950);
DISPLAY 0.468085 (-7000 1950);
PAINT GREEN (-7000 1950);
DISPLAY INVISIBLE (-7000 1950);
FORCEPROP 1 LAST PATH I102
J 2
(-7000 1950);
DISPLAY 0.723404 (-7000 1950);
DISPLAY INVISIBLE (-7000 1950);
FORCEPROP 1 LAST PART_NUMBER SP_CH4221MEE01
J 2
(-7116 2038);
DISPLAY 0.574468 (-7116 2038);
PAINT GREEN (-7116 2038);
DISPLAY INVISIBLE (-7116 2038);
FORCEPROP 1 LAST LOCATION C6680
J 0
(-6750 2025);
DISPLAY 1.021277 (-6750 2025);
DISPLAY INVISIBLE (-6750 2025);
FORCEADD Q_CAP_DIFFBUS..2
R 2
(-7000 2150);
FORCEPROP 1 LAST LOCATION C6678
J 2
(-6725 2150);
DISPLAY 0.723404 (-6725 2150);
PAINT GREEN (-6725 2150);
FORCEPROP 2 LAST $SEC 1
J 2
(-6825 2225);
DISPLAY 0.680851 (-6825 2225);
PAINT MONO (-6825 2225);
DISPLAY INVISIBLE (-6825 2225);
FORCEPROP 2 LAST CDS_SEC 1
J 2
(-6825 2225);
DISPLAY 0.680851 (-6825 2225);
DISPLAY INVISIBLE (-6825 2225);
FORCEPROP 2 LASTPIN (-6925 2150) $PN 1
J 0
(-6915 2160);
DISPLAY 0.808511 (-6915 2160);
FORCEPROP 2 LASTPIN (-7075 2150) $PN 2
J 2
(-7085 2160);
DISPLAY 0.808511 (-7085 2160);
FORCEPROP 2 LAST VALUE DIFF BUS_0.22UF
J 2
(-7150 2150);
DISPLAY 0.553191 (-7150 2150);
FORCEPROP 2 LAST TOLERANCE 20%
J 2
(-7075 2200);
DISPLAY 0.553191 (-7075 2200);
DISPLAY INVISIBLE (-7075 2200);
FORCEPROP 2 LAST PACK_TYPE C0201
J 2
(-7175 2200);
DISPLAY 0.553191 (-7175 2200);
DISPLAY INVISIBLE (-7175 2200);
FORCEPROP 1 LAST MATERIAL X6S
J 2
(-6991 2229);
DISPLAY 0.574468 (-6991 2229);
PAINT GREEN (-6991 2229);
DISPLAY INVISIBLE (-6991 2229);
FORCEPROP 2 LAST VOLTAGE 6.3V
J 2
(-7350 2200);
DISPLAY 0.553191 (-7350 2200);
DISPLAY INVISIBLE (-7350 2200);
FORCEPROP 1 LAST PIN_NAMES_ROTATE TRUE
J 2
(-7000 2150);
DISPLAY 0.489362 (-7000 2150);
PAINT GREEN (-7000 2150);
DISPLAY INVISIBLE (-7000 2150);
FORCEPROP 2 LAST CDS_LIB pure_quanta
J 2
(-7000 2150);
DISPLAY INVISIBLE (-7000 2150);
FORCEPROP 1 LAST CDS_LMAN_SYM_OUTLINE -25,50,25,-50
J 2
(-7000 2150);
DISPLAY 0.468085 (-7000 2150);
PAINT GREEN (-7000 2150);
DISPLAY INVISIBLE (-7000 2150);
FORCEPROP 1 LAST PATH I103
J 2
(-7000 2150);
DISPLAY 0.723404 (-7000 2150);
DISPLAY INVISIBLE (-7000 2150);
FORCEPROP 1 LAST PART_NUMBER SP_CH4221MEE01
J 2
(-7116 2238);
DISPLAY 0.574468 (-7116 2238);
PAINT GREEN (-7116 2238);
DISPLAY INVISIBLE (-7116 2238);
FORCEPROP 1 LAST LOCATION C6678
J 0
(-6750 2225);
DISPLAY 1.021277 (-6750 2225);
DISPLAY INVISIBLE (-6750 2225);
FORCEADD Q_CAP_DIFFBUS..2
R 2
(-7000 2200);
FORCEPROP 1 LAST LOCATION C6677
J 2
(-6725 2200);
DISPLAY 0.723404 (-6725 2200);
PAINT GREEN (-6725 2200);
FORCEPROP 2 LAST $SEC 1
J 2
(-6825 2275);
DISPLAY 0.680851 (-6825 2275);
PAINT MONO (-6825 2275);
DISPLAY INVISIBLE (-6825 2275);
FORCEPROP 2 LAST CDS_SEC 1
J 2
(-6825 2275);
DISPLAY 0.680851 (-6825 2275);
DISPLAY INVISIBLE (-6825 2275);
FORCEPROP 2 LASTPIN (-6925 2200) $PN 1
J 0
(-6915 2210);
DISPLAY 0.808511 (-6915 2210);
FORCEPROP 2 LASTPIN (-7075 2200) $PN 2
J 2
(-7085 2210);
DISPLAY 0.808511 (-7085 2210);
FORCEPROP 2 LAST VALUE DIFF BUS_0.22UF
J 2
(-7150 2200);
DISPLAY 0.553191 (-7150 2200);
FORCEPROP 2 LAST PACK_TYPE C0201
J 2
(-7050 2350);
DISPLAY 0.553191 (-7050 2350);
PAINT GREEN (-7050 2350);
FORCEPROP 2 LAST TOLERANCE 20%
J 2
(-6950 2350);
DISPLAY 0.553191 (-6950 2350);
PAINT GREEN (-6950 2350);
FORCEPROP 1 LAST MATERIAL X6S
J 2
(-7091 2404);
DISPLAY 0.574468 (-7091 2404);
PAINT GREEN (-7091 2404);
FORCEPROP 2 LAST VOLTAGE 6.3V
J 2
(-6825 2350);
DISPLAY 0.553191 (-6825 2350);
PAINT GREEN (-6825 2350);
FORCEPROP 1 LAST PIN_NAMES_ROTATE TRUE
J 2
(-7000 2200);
DISPLAY 0.489362 (-7000 2200);
PAINT GREEN (-7000 2200);
DISPLAY INVISIBLE (-7000 2200);
FORCEPROP 1 LAST CDS_LMAN_SYM_OUTLINE -25,50,25,-50
J 2
(-7000 2200);
DISPLAY 0.468085 (-7000 2200);
PAINT GREEN (-7000 2200);
DISPLAY INVISIBLE (-7000 2200);
FORCEPROP 2 LAST CDS_LIB pure_quanta
J 2
(-7000 2200);
DISPLAY INVISIBLE (-7000 2200);
FORCEPROP 1 LAST PATH I104
J 2
(-7000 2200);
DISPLAY 0.723404 (-7000 2200);
DISPLAY INVISIBLE (-7000 2200);
FORCEPROP 1 LAST PART_NUMBER SP_CH4221MEE01
J 2
(-6816 2288);
DISPLAY 0.574468 (-6816 2288);
PAINT GREEN (-6816 2288);
DISPLAY INVISIBLE (-6816 2288);
FORCEPROP 1 LAST LOCATION C6677
J 0
(-6750 2275);
DISPLAY 1.021277 (-6750 2275);
DISPLAY INVISIBLE (-6750 2275);
FORCEADD TAP..1
R 2
(-7725 2200);
FORCEPROP 3 LASTPIN (-7675 2200) SIG_NAME P5E_CPU1_P1_TX_BUF_DP<8>
J 0
(-7665 2210);
DISPLAY 0.659574 (-7665 2210);
PAINT MONO (-7665 2210);
DISPLAY INVISIBLE (-7665 2210);
FORCEPROP 1 LASTPIN (-7675 2200) BN 8
J 2
(-7663 2208);
DISPLAY 0.680851 (-7663 2208);
PAINT GREEN (-7663 2208);
FORCEPROP 2 LAST CDS_LIB standard
J 0
(-7725 2200);
DISPLAY INVISIBLE (-7725 2200);
FORCEPROP 1 LAST BODY_TYPE PLUMBING
J 2
(-7725 2250);
DISPLAY 0.872340 (-7725 2250);
PAINT GREEN (-7725 2250);
DISPLAY INVISIBLE (-7725 2250);
FORCEPROP 1 LAST HDL_TAP TRUE
J 2
(-8050 2075);
DISPLAY 0.872340 (-8050 2075);
DISPLAY INVISIBLE (-8050 2075);
FORCEPROP 1 LAST PATH I105
J 2
(-7723 2200);
DISPLAY 0.872340 (-7723 2200);
PAINT GREEN (-7723 2200);
DISPLAY INVISIBLE (-7723 2200);
FORCEADD TAP..1
(-6450 800);
FORCEPROP 3 LASTPIN (-6500 800) SIG_NAME P5E_CPU1_P1_TX_BUF_C_DP<15>
J 0
(-6490 810);
DISPLAY 0.659574 (-6490 810);
PAINT MONO (-6490 810);
DISPLAY INVISIBLE (-6490 810);
FORCEPROP 1 LASTPIN (-6500 800) BN 15
J 0
(-6512 808);
DISPLAY 0.680851 (-6512 808);
PAINT GREEN (-6512 808);
FORCEPROP 2 LAST CDS_LIB standard
J 0
(-6450 800);
DISPLAY INVISIBLE (-6450 800);
FORCEPROP 1 LAST BODY_TYPE PLUMBING
J 0
(-6450 850);
DISPLAY 0.872340 (-6450 850);
PAINT GREEN (-6450 850);
DISPLAY INVISIBLE (-6450 850);
FORCEPROP 1 LAST HDL_TAP TRUE
J 0
(-6125 675);
DISPLAY 0.872340 (-6125 675);
DISPLAY INVISIBLE (-6125 675);
FORCEPROP 1 LAST PATH I106
J 0
(-6452 800);
DISPLAY 0.872340 (-6452 800);
PAINT GREEN (-6452 800);
DISPLAY INVISIBLE (-6452 800);
FORCEADD TAP..1
(-6250 750);
FORCEPROP 3 LASTPIN (-6300 750) SIG_NAME P5E_CPU1_P1_TX_BUF_C_DN<15>
J 0
(-6290 760);
DISPLAY 0.659574 (-6290 760);
PAINT MONO (-6290 760);
DISPLAY INVISIBLE (-6290 760);
FORCEPROP 1 LASTPIN (-6300 750) BN 15
J 0
(-6312 758);
DISPLAY 0.680851 (-6312 758);
PAINT GREEN (-6312 758);
FORCEPROP 2 LAST CDS_LIB standard
J 0
(-6250 750);
DISPLAY INVISIBLE (-6250 750);
FORCEPROP 1 LAST BODY_TYPE PLUMBING
J 0
(-6250 800);
DISPLAY 0.872340 (-6250 800);
PAINT GREEN (-6250 800);
DISPLAY INVISIBLE (-6250 800);
FORCEPROP 1 LAST HDL_TAP TRUE
J 0
(-5925 625);
DISPLAY 0.872340 (-5925 625);
DISPLAY INVISIBLE (-5925 625);
FORCEPROP 1 LAST PATH I107
J 0
(-6252 750);
DISPLAY 0.872340 (-6252 750);
PAINT GREEN (-6252 750);
DISPLAY INVISIBLE (-6252 750);
FORCEADD TAP..1
(-6450 1000);
FORCEPROP 3 LASTPIN (-6500 1000) SIG_NAME P5E_CPU1_P1_TX_BUF_C_DP<14>
J 0
(-6490 1010);
DISPLAY 0.659574 (-6490 1010);
PAINT MONO (-6490 1010);
DISPLAY INVISIBLE (-6490 1010);
FORCEPROP 1 LASTPIN (-6500 1000) BN 14
J 0
(-6512 1008);
DISPLAY 0.680851 (-6512 1008);
PAINT GREEN (-6512 1008);
FORCEPROP 2 LAST CDS_LIB standard
J 0
(-6450 1000);
DISPLAY INVISIBLE (-6450 1000);
FORCEPROP 1 LAST BODY_TYPE PLUMBING
J 0
(-6450 1050);
DISPLAY 0.872340 (-6450 1050);
PAINT GREEN (-6450 1050);
DISPLAY INVISIBLE (-6450 1050);
FORCEPROP 1 LAST HDL_TAP TRUE
J 0
(-6125 875);
DISPLAY 0.872340 (-6125 875);
DISPLAY INVISIBLE (-6125 875);
FORCEPROP 1 LAST PATH I108
J 0
(-6452 1000);
DISPLAY 0.872340 (-6452 1000);
PAINT GREEN (-6452 1000);
DISPLAY INVISIBLE (-6452 1000);
FORCEADD TAP..1
(-6250 950);
FORCEPROP 3 LASTPIN (-6300 950) SIG_NAME P5E_CPU1_P1_TX_BUF_C_DN<14>
J 0
(-6290 960);
DISPLAY 0.659574 (-6290 960);
PAINT MONO (-6290 960);
DISPLAY INVISIBLE (-6290 960);
FORCEPROP 1 LASTPIN (-6300 950) BN 14
J 0
(-6312 958);
DISPLAY 0.680851 (-6312 958);
PAINT GREEN (-6312 958);
FORCEPROP 2 LAST CDS_LIB standard
J 0
(-6250 950);
DISPLAY INVISIBLE (-6250 950);
FORCEPROP 1 LAST BODY_TYPE PLUMBING
J 0
(-6250 1000);
DISPLAY 0.872340 (-6250 1000);
PAINT GREEN (-6250 1000);
DISPLAY INVISIBLE (-6250 1000);
FORCEPROP 1 LAST HDL_TAP TRUE
J 0
(-5925 825);
DISPLAY 0.872340 (-5925 825);
DISPLAY INVISIBLE (-5925 825);
FORCEPROP 1 LAST PATH I109
J 0
(-6252 950);
DISPLAY 0.872340 (-6252 950);
PAINT GREEN (-6252 950);
DISPLAY INVISIBLE (-6252 950);
FORCEADD TAP..1
R 2
(-3350 1950);
FORCEPROP 3 LASTPIN (-3300 1950) SIG_NAME P5E_CPU1_P1_TX_BUF_DN<1>
J 0
(-3290 1960);
DISPLAY 0.659574 (-3290 1960);
PAINT MONO (-3290 1960);
DISPLAY INVISIBLE (-3290 1960);
FORCEPROP 1 LASTPIN (-3300 1950) BN 1
J 2
(-3288 1958);
DISPLAY 0.680851 (-3288 1958);
PAINT GREEN (-3288 1958);
FORCEPROP 2 LAST CDS_LIB standard
J 0
(-3350 1950);
DISPLAY INVISIBLE (-3350 1950);
FORCEPROP 1 LAST BODY_TYPE PLUMBING
J 2
(-3350 2000);
DISPLAY 0.872340 (-3350 2000);
PAINT GREEN (-3350 2000);
DISPLAY INVISIBLE (-3350 2000);
FORCEPROP 1 LAST HDL_TAP TRUE
J 2
(-3675 1825);
DISPLAY 0.872340 (-3675 1825);
DISPLAY INVISIBLE (-3675 1825);
FORCEPROP 1 LAST PATH I11
J 2
(-3348 1950);
DISPLAY 0.872340 (-3348 1950);
PAINT GREEN (-3348 1950);
DISPLAY INVISIBLE (-3348 1950);
FORCEADD TAP..1
(-6250 1150);
FORCEPROP 3 LASTPIN (-6300 1150) SIG_NAME P5E_CPU1_P1_TX_BUF_C_DN<13>
J 0
(-6290 1160);
DISPLAY 0.659574 (-6290 1160);
PAINT MONO (-6290 1160);
DISPLAY INVISIBLE (-6290 1160);
FORCEPROP 1 LASTPIN (-6300 1150) BN 13
J 0
(-6312 1158);
DISPLAY 0.680851 (-6312 1158);
PAINT GREEN (-6312 1158);
FORCEPROP 2 LAST CDS_LIB standard
J 0
(-6250 1150);
DISPLAY INVISIBLE (-6250 1150);
FORCEPROP 1 LAST BODY_TYPE PLUMBING
J 0
(-6250 1200);
DISPLAY 0.872340 (-6250 1200);
PAINT GREEN (-6250 1200);
DISPLAY INVISIBLE (-6250 1200);
FORCEPROP 1 LAST HDL_TAP TRUE
J 0
(-5925 1025);
DISPLAY 0.872340 (-5925 1025);
DISPLAY INVISIBLE (-5925 1025);
FORCEPROP 1 LAST PATH I110
J 0
(-6252 1150);
DISPLAY 0.872340 (-6252 1150);
PAINT GREEN (-6252 1150);
DISPLAY INVISIBLE (-6252 1150);
FORCEADD TAP..1
(-6450 1200);
FORCEPROP 3 LASTPIN (-6500 1200) SIG_NAME P5E_CPU1_P1_TX_BUF_C_DP<13>
J 0
(-6490 1210);
DISPLAY 0.659574 (-6490 1210);
PAINT MONO (-6490 1210);
DISPLAY INVISIBLE (-6490 1210);
FORCEPROP 1 LASTPIN (-6500 1200) BN 13
J 0
(-6512 1208);
DISPLAY 0.680851 (-6512 1208);
PAINT GREEN (-6512 1208);
FORCEPROP 2 LAST CDS_LIB standard
J 0
(-6450 1200);
DISPLAY INVISIBLE (-6450 1200);
FORCEPROP 1 LAST BODY_TYPE PLUMBING
J 0
(-6450 1250);
DISPLAY 0.872340 (-6450 1250);
PAINT GREEN (-6450 1250);
DISPLAY INVISIBLE (-6450 1250);
FORCEPROP 1 LAST HDL_TAP TRUE
J 0
(-6125 1075);
DISPLAY 0.872340 (-6125 1075);
DISPLAY INVISIBLE (-6125 1075);
FORCEPROP 1 LAST PATH I111
J 0
(-6452 1200);
DISPLAY 0.872340 (-6452 1200);
PAINT GREEN (-6452 1200);
DISPLAY INVISIBLE (-6452 1200);
FORCEADD TAP..1
(-6450 1400);
FORCEPROP 3 LASTPIN (-6500 1400) SIG_NAME P5E_CPU1_P1_TX_BUF_C_DP<12>
J 0
(-6490 1410);
DISPLAY 0.659574 (-6490 1410);
PAINT MONO (-6490 1410);
DISPLAY INVISIBLE (-6490 1410);
FORCEPROP 1 LASTPIN (-6500 1400) BN 12
J 0
(-6512 1408);
DISPLAY 0.680851 (-6512 1408);
PAINT GREEN (-6512 1408);
FORCEPROP 2 LAST CDS_LIB standard
J 0
(-6450 1400);
DISPLAY INVISIBLE (-6450 1400);
FORCEPROP 1 LAST BODY_TYPE PLUMBING
J 0
(-6450 1450);
DISPLAY 0.872340 (-6450 1450);
PAINT GREEN (-6450 1450);
DISPLAY INVISIBLE (-6450 1450);
FORCEPROP 1 LAST HDL_TAP TRUE
J 0
(-6125 1275);
DISPLAY 0.872340 (-6125 1275);
DISPLAY INVISIBLE (-6125 1275);
FORCEPROP 1 LAST PATH I112
J 0
(-6452 1400);
DISPLAY 0.872340 (-6452 1400);
PAINT GREEN (-6452 1400);
DISPLAY INVISIBLE (-6452 1400);
FORCEADD TAP..1
(-6250 1350);
FORCEPROP 3 LASTPIN (-6300 1350) SIG_NAME P5E_CPU1_P1_TX_BUF_C_DN<12>
J 0
(-6290 1360);
DISPLAY 0.659574 (-6290 1360);
PAINT MONO (-6290 1360);
DISPLAY INVISIBLE (-6290 1360);
FORCEPROP 1 LASTPIN (-6300 1350) BN 12
J 0
(-6312 1358);
DISPLAY 0.680851 (-6312 1358);
PAINT GREEN (-6312 1358);
FORCEPROP 2 LAST CDS_LIB standard
J 0
(-6250 1350);
DISPLAY INVISIBLE (-6250 1350);
FORCEPROP 1 LAST BODY_TYPE PLUMBING
J 0
(-6250 1400);
DISPLAY 0.872340 (-6250 1400);
PAINT GREEN (-6250 1400);
DISPLAY INVISIBLE (-6250 1400);
FORCEPROP 1 LAST HDL_TAP TRUE
J 0
(-5925 1225);
DISPLAY 0.872340 (-5925 1225);
DISPLAY INVISIBLE (-5925 1225);
FORCEPROP 1 LAST PATH I113
J 0
(-6252 1350);
DISPLAY 0.872340 (-6252 1350);
PAINT GREEN (-6252 1350);
DISPLAY INVISIBLE (-6252 1350);
FORCEADD TAP..1
(-6250 1550);
FORCEPROP 3 LASTPIN (-6300 1550) SIG_NAME P5E_CPU1_P1_TX_BUF_C_DN<11>
J 0
(-6290 1560);
DISPLAY 0.659574 (-6290 1560);
PAINT MONO (-6290 1560);
DISPLAY INVISIBLE (-6290 1560);
FORCEPROP 1 LASTPIN (-6300 1550) BN 11
J 0
(-6312 1558);
DISPLAY 0.680851 (-6312 1558);
PAINT GREEN (-6312 1558);
FORCEPROP 2 LAST CDS_LIB standard
J 0
(-6250 1550);
DISPLAY INVISIBLE (-6250 1550);
FORCEPROP 1 LAST BODY_TYPE PLUMBING
J 0
(-6250 1600);
DISPLAY 0.872340 (-6250 1600);
PAINT GREEN (-6250 1600);
DISPLAY INVISIBLE (-6250 1600);
FORCEPROP 1 LAST HDL_TAP TRUE
J 0
(-5925 1425);
DISPLAY 0.872340 (-5925 1425);
DISPLAY INVISIBLE (-5925 1425);
FORCEPROP 1 LAST PATH I114
J 0
(-6252 1550);
DISPLAY 0.872340 (-6252 1550);
PAINT GREEN (-6252 1550);
DISPLAY INVISIBLE (-6252 1550);
FORCEADD TAP..1
(-6450 1600);
FORCEPROP 3 LASTPIN (-6500 1600) SIG_NAME P5E_CPU1_P1_TX_BUF_C_DP<11>
J 0
(-6490 1610);
DISPLAY 0.659574 (-6490 1610);
PAINT MONO (-6490 1610);
DISPLAY INVISIBLE (-6490 1610);
FORCEPROP 1 LASTPIN (-6500 1600) BN 11
J 0
(-6512 1608);
DISPLAY 0.680851 (-6512 1608);
PAINT GREEN (-6512 1608);
FORCEPROP 2 LAST CDS_LIB standard
J 0
(-6450 1600);
DISPLAY INVISIBLE (-6450 1600);
FORCEPROP 1 LAST BODY_TYPE PLUMBING
J 0
(-6450 1650);
DISPLAY 0.872340 (-6450 1650);
PAINT GREEN (-6450 1650);
DISPLAY INVISIBLE (-6450 1650);
FORCEPROP 1 LAST HDL_TAP TRUE
J 0
(-6125 1475);
DISPLAY 0.872340 (-6125 1475);
DISPLAY INVISIBLE (-6125 1475);
FORCEPROP 1 LAST PATH I115
J 0
(-6452 1600);
DISPLAY 0.872340 (-6452 1600);
PAINT GREEN (-6452 1600);
DISPLAY INVISIBLE (-6452 1600);
FORCEADD TAP..1
(-6450 1800);
FORCEPROP 3 LASTPIN (-6500 1800) SIG_NAME P5E_CPU1_P1_TX_BUF_C_DP<10>
J 0
(-6490 1810);
DISPLAY 0.659574 (-6490 1810);
PAINT MONO (-6490 1810);
DISPLAY INVISIBLE (-6490 1810);
FORCEPROP 1 LASTPIN (-6500 1800) BN 10
J 0
(-6512 1808);
DISPLAY 0.680851 (-6512 1808);
PAINT GREEN (-6512 1808);
FORCEPROP 2 LAST CDS_LIB standard
J 0
(-6450 1800);
DISPLAY INVISIBLE (-6450 1800);
FORCEPROP 1 LAST BODY_TYPE PLUMBING
J 0
(-6450 1850);
DISPLAY 0.872340 (-6450 1850);
PAINT GREEN (-6450 1850);
DISPLAY INVISIBLE (-6450 1850);
FORCEPROP 1 LAST HDL_TAP TRUE
J 0
(-6125 1675);
DISPLAY 0.872340 (-6125 1675);
DISPLAY INVISIBLE (-6125 1675);
FORCEPROP 1 LAST PATH I116
J 0
(-6452 1800);
DISPLAY 0.872340 (-6452 1800);
PAINT GREEN (-6452 1800);
DISPLAY INVISIBLE (-6452 1800);
FORCEADD TAP..1
(-6250 1750);
FORCEPROP 3 LASTPIN (-6300 1750) SIG_NAME P5E_CPU1_P1_TX_BUF_C_DN<10>
J 0
(-6290 1760);
DISPLAY 0.659574 (-6290 1760);
PAINT MONO (-6290 1760);
DISPLAY INVISIBLE (-6290 1760);
FORCEPROP 1 LASTPIN (-6300 1750) BN 10
J 0
(-6312 1758);
DISPLAY 0.680851 (-6312 1758);
PAINT GREEN (-6312 1758);
FORCEPROP 2 LAST CDS_LIB standard
J 0
(-6250 1750);
DISPLAY INVISIBLE (-6250 1750);
FORCEPROP 1 LAST BODY_TYPE PLUMBING
J 0
(-6250 1800);
DISPLAY 0.872340 (-6250 1800);
PAINT GREEN (-6250 1800);
DISPLAY INVISIBLE (-6250 1800);
FORCEPROP 1 LAST HDL_TAP TRUE
J 0
(-5925 1625);
DISPLAY 0.872340 (-5925 1625);
DISPLAY INVISIBLE (-5925 1625);
FORCEPROP 1 LAST PATH I117
J 0
(-6252 1750);
DISPLAY 0.872340 (-6252 1750);
PAINT GREEN (-6252 1750);
DISPLAY INVISIBLE (-6252 1750);
FORCEADD TAP..1
(-6450 2000);
FORCEPROP 3 LASTPIN (-6500 2000) SIG_NAME P5E_CPU1_P1_TX_BUF_C_DP<9>
J 0
(-6490 2010);
DISPLAY 0.659574 (-6490 2010);
PAINT MONO (-6490 2010);
DISPLAY INVISIBLE (-6490 2010);
FORCEPROP 1 LASTPIN (-6500 2000) BN 9
J 0
(-6512 2008);
DISPLAY 0.680851 (-6512 2008);
PAINT GREEN (-6512 2008);
FORCEPROP 2 LAST CDS_LIB standard
J 0
(-6450 2000);
DISPLAY INVISIBLE (-6450 2000);
FORCEPROP 1 LAST BODY_TYPE PLUMBING
J 0
(-6450 2050);
DISPLAY 0.872340 (-6450 2050);
PAINT GREEN (-6450 2050);
DISPLAY INVISIBLE (-6450 2050);
FORCEPROP 1 LAST HDL_TAP TRUE
J 0
(-6125 1875);
DISPLAY 0.872340 (-6125 1875);
DISPLAY INVISIBLE (-6125 1875);
FORCEPROP 1 LAST PATH I118
J 0
(-6452 2000);
DISPLAY 0.872340 (-6452 2000);
PAINT GREEN (-6452 2000);
DISPLAY INVISIBLE (-6452 2000);
FORCEADD TAP..1
(-6250 2150);
FORCEPROP 3 LASTPIN (-6300 2150) SIG_NAME P5E_CPU1_P1_TX_BUF_C_DN<8>
J 0
(-6290 2160);
DISPLAY 0.659574 (-6290 2160);
PAINT MONO (-6290 2160);
DISPLAY INVISIBLE (-6290 2160);
FORCEPROP 1 LASTPIN (-6300 2150) BN 8
J 0
(-6312 2158);
DISPLAY 0.680851 (-6312 2158);
PAINT GREEN (-6312 2158);
FORCEPROP 2 LAST CDS_LIB standard
J 0
(-6250 2150);
DISPLAY INVISIBLE (-6250 2150);
FORCEPROP 1 LAST BODY_TYPE PLUMBING
J 0
(-6250 2200);
DISPLAY 0.872340 (-6250 2200);
PAINT GREEN (-6250 2200);
DISPLAY INVISIBLE (-6250 2200);
FORCEPROP 1 LAST HDL_TAP TRUE
J 0
(-5925 2025);
DISPLAY 0.872340 (-5925 2025);
DISPLAY INVISIBLE (-5925 2025);
FORCEPROP 1 LAST PATH I119
J 0
(-6252 2150);
DISPLAY 0.872340 (-6252 2150);
PAINT GREEN (-6252 2150);
DISPLAY INVISIBLE (-6252 2150);
FORCEADD TAP..1
R 2
(-3100 1200);
FORCEPROP 3 LASTPIN (-3050 1200) SIG_NAME P5E_CPU1_P1_TX_BUF_DP<5>
J 0
(-3040 1210);
DISPLAY 0.659574 (-3040 1210);
PAINT MONO (-3040 1210);
DISPLAY INVISIBLE (-3040 1210);
FORCEPROP 1 LASTPIN (-3050 1200) BN 5
J 2
(-3038 1208);
DISPLAY 0.680851 (-3038 1208);
PAINT GREEN (-3038 1208);
FORCEPROP 2 LAST CDS_LIB standard
J 0
(-3100 1200);
DISPLAY INVISIBLE (-3100 1200);
FORCEPROP 1 LAST BODY_TYPE PLUMBING
J 2
(-3100 1250);
DISPLAY 0.872340 (-3100 1250);
PAINT GREEN (-3100 1250);
DISPLAY INVISIBLE (-3100 1250);
FORCEPROP 1 LAST HDL_TAP TRUE
J 2
(-3425 1075);
DISPLAY 0.872340 (-3425 1075);
DISPLAY INVISIBLE (-3425 1075);
FORCEPROP 1 LAST PATH I12
J 2
(-3098 1200);
DISPLAY 0.872340 (-3098 1200);
PAINT GREEN (-3098 1200);
DISPLAY INVISIBLE (-3098 1200);
FORCEADD TAP..1
(-6250 1950);
FORCEPROP 3 LASTPIN (-6300 1950) SIG_NAME P5E_CPU1_P1_TX_BUF_C_DN<9>
J 0
(-6290 1960);
DISPLAY 0.659574 (-6290 1960);
PAINT MONO (-6290 1960);
DISPLAY INVISIBLE (-6290 1960);
FORCEPROP 1 LASTPIN (-6300 1950) BN 9
J 0
(-6312 1958);
DISPLAY 0.680851 (-6312 1958);
PAINT GREEN (-6312 1958);
FORCEPROP 2 LAST CDS_LIB standard
J 0
(-6250 1950);
DISPLAY INVISIBLE (-6250 1950);
FORCEPROP 1 LAST BODY_TYPE PLUMBING
J 0
(-6250 2000);
DISPLAY 0.872340 (-6250 2000);
PAINT GREEN (-6250 2000);
DISPLAY INVISIBLE (-6250 2000);
FORCEPROP 1 LAST HDL_TAP TRUE
J 0
(-5925 1825);
DISPLAY 0.872340 (-5925 1825);
DISPLAY INVISIBLE (-5925 1825);
FORCEPROP 1 LAST PATH I120
J 0
(-6252 1950);
DISPLAY 0.872340 (-6252 1950);
PAINT GREEN (-6252 1950);
DISPLAY INVISIBLE (-6252 1950);
FORCEADD OFFPAGE..2
(-5250 2175);
FORCEPROP 2 LAST $XR0 121 
J 0
(-5061 2175);
DISPLAY 0.638298 (-5061 2175);
PAINT MONO (-5061 2175);
FORCEPROP 2 LAST CDS_LIB standard
J 0
(-5250 2175);
DISPLAY INVISIBLE (-5250 2175);
FORCEPROP 1 LAST OFFPAGE TRUE
J 0
(-4925 2050);
DISPLAY 0.872340 (-4925 2050);
DISPLAY INVISIBLE (-4925 2050);
FORCEPROP 1 LAST COMMENT_BODY TRUE
J 0
(-5295 2080);
DISPLAY 0.872340 (-5295 2080);
PAINT GREEN (-5295 2080);
DISPLAY INVISIBLE (-5295 2080);
FORCEPROP 2 LAST PATH I121
J 0
(-5050 2225);
DISPLAY 0.680851 (-5050 2225);
DISPLAY INVISIBLE (-5050 2225);
FORCEADD OFFPAGE..2
(-5250 2225);
FORCEPROP 2 LAST $XR0 121 
J 0
(-5061 2225);
DISPLAY 0.638298 (-5061 2225);
PAINT MONO (-5061 2225);
FORCEPROP 2 LAST CDS_LIB standard
J 0
(-5250 2225);
DISPLAY INVISIBLE (-5250 2225);
FORCEPROP 1 LAST OFFPAGE TRUE
J 0
(-4925 2100);
DISPLAY 0.872340 (-4925 2100);
DISPLAY INVISIBLE (-4925 2100);
FORCEPROP 1 LAST COMMENT_BODY TRUE
J 0
(-5295 2130);
DISPLAY 0.872340 (-5295 2130);
PAINT GREEN (-5295 2130);
DISPLAY INVISIBLE (-5295 2130);
FORCEPROP 2 LAST PATH I122
J 0
(-5050 2275);
DISPLAY 0.680851 (-5050 2275);
DISPLAY INVISIBLE (-5050 2275);
FORCEADD TAP..1
(-6450 2200);
FORCEPROP 3 LASTPIN (-6500 2200) SIG_NAME P5E_CPU1_P1_TX_BUF_C_DP<8>
J 0
(-6490 2210);
DISPLAY 0.659574 (-6490 2210);
PAINT MONO (-6490 2210);
DISPLAY INVISIBLE (-6490 2210);
FORCEPROP 1 LASTPIN (-6500 2200) BN 8
J 0
(-6512 2208);
DISPLAY 0.680851 (-6512 2208);
PAINT GREEN (-6512 2208);
FORCEPROP 2 LAST CDS_LIB standard
J 0
(-6450 2200);
DISPLAY INVISIBLE (-6450 2200);
FORCEPROP 1 LAST BODY_TYPE PLUMBING
J 0
(-6450 2250);
DISPLAY 0.872340 (-6450 2250);
PAINT GREEN (-6450 2250);
DISPLAY INVISIBLE (-6450 2250);
FORCEPROP 1 LAST HDL_TAP TRUE
J 0
(-6125 2075);
DISPLAY 0.872340 (-6125 2075);
DISPLAY INVISIBLE (-6125 2075);
FORCEPROP 1 LAST PATH I123
J 0
(-6452 2200);
DISPLAY 0.872340 (-6452 2200);
PAINT GREEN (-6452 2200);
DISPLAY INVISIBLE (-6452 2200);
FORCEADD TAP..1
(-1625 3350);
FORCEPROP 3 LASTPIN (-1675 3350) SIG_NAME P5E_CPU1_P1_TX_BUF_DP<0>
J 0
(-1665 3360);
DISPLAY 0.659574 (-1665 3360);
PAINT MONO (-1665 3360);
DISPLAY INVISIBLE (-1665 3360);
FORCEPROP 1 LASTPIN (-1675 3350) BN 0
J 0
(-1687 3358);
DISPLAY 0.680851 (-1687 3358);
PAINT GREEN (-1687 3358);
FORCEPROP 2 LAST CDS_LIB standard
J 0
(-1625 3350);
DISPLAY INVISIBLE (-1625 3350);
FORCEPROP 1 LAST BODY_TYPE PLUMBING
J 0
(-1625 3400);
DISPLAY 0.872340 (-1625 3400);
PAINT GREEN (-1625 3400);
DISPLAY INVISIBLE (-1625 3400);
FORCEPROP 1 LAST HDL_TAP TRUE
J 0
(-1300 3225);
DISPLAY 0.872340 (-1300 3225);
DISPLAY INVISIBLE (-1300 3225);
FORCEPROP 1 LAST PATH I124
J 0
(-1627 3350);
DISPLAY 0.872340 (-1627 3350);
PAINT GREEN (-1627 3350);
DISPLAY INVISIBLE (-1627 3350);
FORCEADD TAP..1
(-1425 3250);
FORCEPROP 3 LASTPIN (-1475 3250) SIG_NAME P5E_CPU1_P1_TX_BUF_DN<0>
J 0
(-1465 3260);
DISPLAY 0.659574 (-1465 3260);
PAINT MONO (-1465 3260);
DISPLAY INVISIBLE (-1465 3260);
FORCEPROP 1 LASTPIN (-1475 3250) BN 0
J 0
(-1487 3258);
DISPLAY 0.680851 (-1487 3258);
PAINT GREEN (-1487 3258);
FORCEPROP 2 LAST CDS_LIB standard
J 0
(-1425 3250);
DISPLAY INVISIBLE (-1425 3250);
FORCEPROP 1 LAST BODY_TYPE PLUMBING
J 0
(-1425 3300);
DISPLAY 0.872340 (-1425 3300);
PAINT GREEN (-1425 3300);
DISPLAY INVISIBLE (-1425 3300);
FORCEPROP 1 LAST HDL_TAP TRUE
J 0
(-1100 3125);
DISPLAY 0.872340 (-1100 3125);
DISPLAY INVISIBLE (-1100 3125);
FORCEPROP 1 LAST PATH I125
J 0
(-1427 3250);
DISPLAY 0.872340 (-1427 3250);
PAINT GREEN (-1427 3250);
DISPLAY INVISIBLE (-1427 3250);
FORCEADD TAP..1
(-1425 3600);
FORCEPROP 3 LASTPIN (-1475 3600) SIG_NAME P5E_CPU1_P1_TX_BUF_DN<1>
J 0
(-1465 3610);
DISPLAY 0.659574 (-1465 3610);
PAINT MONO (-1465 3610);
DISPLAY INVISIBLE (-1465 3610);
FORCEPROP 1 LASTPIN (-1475 3600) BN 1
J 0
(-1487 3608);
DISPLAY 0.680851 (-1487 3608);
PAINT GREEN (-1487 3608);
FORCEPROP 2 LAST CDS_LIB standard
J 0
(-1425 3600);
DISPLAY INVISIBLE (-1425 3600);
FORCEPROP 1 LAST BODY_TYPE PLUMBING
J 0
(-1425 3650);
DISPLAY 0.872340 (-1425 3650);
PAINT GREEN (-1425 3650);
DISPLAY INVISIBLE (-1425 3650);
FORCEPROP 1 LAST HDL_TAP TRUE
J 0
(-1100 3475);
DISPLAY 0.872340 (-1100 3475);
DISPLAY INVISIBLE (-1100 3475);
FORCEPROP 1 LAST PATH I126
J 0
(-1427 3600);
DISPLAY 0.872340 (-1427 3600);
PAINT GREEN (-1427 3600);
DISPLAY INVISIBLE (-1427 3600);
FORCEADD TAP..1
(-1625 3700);
FORCEPROP 3 LASTPIN (-1675 3700) SIG_NAME P5E_CPU1_P1_TX_BUF_DP<1>
J 0
(-1665 3710);
DISPLAY 0.659574 (-1665 3710);
PAINT MONO (-1665 3710);
DISPLAY INVISIBLE (-1665 3710);
FORCEPROP 1 LASTPIN (-1675 3700) BN 1
J 0
(-1687 3708);
DISPLAY 0.680851 (-1687 3708);
PAINT GREEN (-1687 3708);
FORCEPROP 2 LAST CDS_LIB standard
J 0
(-1625 3700);
DISPLAY INVISIBLE (-1625 3700);
FORCEPROP 1 LAST BODY_TYPE PLUMBING
J 0
(-1625 3750);
DISPLAY 0.872340 (-1625 3750);
PAINT GREEN (-1625 3750);
DISPLAY INVISIBLE (-1625 3750);
FORCEPROP 1 LAST HDL_TAP TRUE
J 0
(-1300 3575);
DISPLAY 0.872340 (-1300 3575);
DISPLAY INVISIBLE (-1300 3575);
FORCEPROP 1 LAST PATH I127
J 0
(-1627 3700);
DISPLAY 0.872340 (-1627 3700);
PAINT GREEN (-1627 3700);
DISPLAY INVISIBLE (-1627 3700);
FORCEADD TAP..1
(-1625 4050);
FORCEPROP 3 LASTPIN (-1675 4050) SIG_NAME P5E_CPU1_P1_TX_BUF_DP<2>
J 0
(-1665 4060);
DISPLAY 0.659574 (-1665 4060);
PAINT MONO (-1665 4060);
DISPLAY INVISIBLE (-1665 4060);
FORCEPROP 1 LASTPIN (-1675 4050) BN 2
J 0
(-1687 4058);
DISPLAY 0.680851 (-1687 4058);
PAINT GREEN (-1687 4058);
FORCEPROP 2 LAST CDS_LIB standard
J 0
(-1625 4050);
DISPLAY INVISIBLE (-1625 4050);
FORCEPROP 1 LAST BODY_TYPE PLUMBING
J 0
(-1625 4100);
DISPLAY 0.872340 (-1625 4100);
PAINT GREEN (-1625 4100);
DISPLAY INVISIBLE (-1625 4100);
FORCEPROP 1 LAST HDL_TAP TRUE
J 0
(-1300 3925);
DISPLAY 0.872340 (-1300 3925);
DISPLAY INVISIBLE (-1300 3925);
FORCEPROP 1 LAST PATH I128
J 0
(-1627 4050);
DISPLAY 0.872340 (-1627 4050);
PAINT GREEN (-1627 4050);
DISPLAY INVISIBLE (-1627 4050);
FORCEADD TAP..1
(-1425 3950);
FORCEPROP 3 LASTPIN (-1475 3950) SIG_NAME P5E_CPU1_P1_TX_BUF_DN<2>
J 0
(-1465 3960);
DISPLAY 0.659574 (-1465 3960);
PAINT MONO (-1465 3960);
DISPLAY INVISIBLE (-1465 3960);
FORCEPROP 1 LASTPIN (-1475 3950) BN 2
J 0
(-1487 3958);
DISPLAY 0.680851 (-1487 3958);
PAINT GREEN (-1487 3958);
FORCEPROP 2 LAST CDS_LIB standard
J 0
(-1425 3950);
DISPLAY INVISIBLE (-1425 3950);
FORCEPROP 1 LAST BODY_TYPE PLUMBING
J 0
(-1425 4000);
DISPLAY 0.872340 (-1425 4000);
PAINT GREEN (-1425 4000);
DISPLAY INVISIBLE (-1425 4000);
FORCEPROP 1 LAST HDL_TAP TRUE
J 0
(-1100 3825);
DISPLAY 0.872340 (-1100 3825);
DISPLAY INVISIBLE (-1100 3825);
FORCEPROP 1 LAST PATH I129
J 0
(-1427 3950);
DISPLAY 0.872340 (-1427 3950);
PAINT GREEN (-1427 3950);
DISPLAY INVISIBLE (-1427 3950);
FORCEADD TAP..1
R 2
(-3100 1400);
FORCEPROP 3 LASTPIN (-3050 1400) SIG_NAME P5E_CPU1_P1_TX_BUF_DP<4>
J 0
(-3040 1410);
DISPLAY 0.659574 (-3040 1410);
PAINT MONO (-3040 1410);
DISPLAY INVISIBLE (-3040 1410);
FORCEPROP 1 LASTPIN (-3050 1400) BN 4
J 2
(-3038 1408);
DISPLAY 0.680851 (-3038 1408);
PAINT GREEN (-3038 1408);
FORCEPROP 2 LAST CDS_LIB standard
J 0
(-3100 1400);
DISPLAY INVISIBLE (-3100 1400);
FORCEPROP 1 LAST BODY_TYPE PLUMBING
J 2
(-3100 1450);
DISPLAY 0.872340 (-3100 1450);
PAINT GREEN (-3100 1450);
DISPLAY INVISIBLE (-3100 1450);
FORCEPROP 1 LAST HDL_TAP TRUE
J 2
(-3425 1275);
DISPLAY 0.872340 (-3425 1275);
DISPLAY INVISIBLE (-3425 1275);
FORCEPROP 1 LAST PATH I13
J 2
(-3098 1400);
DISPLAY 0.872340 (-3098 1400);
PAINT GREEN (-3098 1400);
DISPLAY INVISIBLE (-3098 1400);
FORCEADD TAP..1
(-1625 4400);
FORCEPROP 3 LASTPIN (-1675 4400) SIG_NAME P5E_CPU1_P1_TX_BUF_DP<3>
J 0
(-1665 4410);
DISPLAY 0.659574 (-1665 4410);
PAINT MONO (-1665 4410);
DISPLAY INVISIBLE (-1665 4410);
FORCEPROP 1 LASTPIN (-1675 4400) BN 3
J 0
(-1687 4408);
DISPLAY 0.680851 (-1687 4408);
PAINT GREEN (-1687 4408);
FORCEPROP 2 LAST CDS_LIB standard
J 0
(-1625 4400);
DISPLAY INVISIBLE (-1625 4400);
FORCEPROP 1 LAST BODY_TYPE PLUMBING
J 0
(-1625 4450);
DISPLAY 0.872340 (-1625 4450);
PAINT GREEN (-1625 4450);
DISPLAY INVISIBLE (-1625 4450);
FORCEPROP 1 LAST HDL_TAP TRUE
J 0
(-1300 4275);
DISPLAY 0.872340 (-1300 4275);
DISPLAY INVISIBLE (-1300 4275);
FORCEPROP 1 LAST PATH I130
J 0
(-1627 4400);
DISPLAY 0.872340 (-1627 4400);
PAINT GREEN (-1627 4400);
DISPLAY INVISIBLE (-1627 4400);
FORCEADD TAP..1
(-1425 4300);
FORCEPROP 3 LASTPIN (-1475 4300) SIG_NAME P5E_CPU1_P1_TX_BUF_DN<3>
J 0
(-1465 4310);
DISPLAY 0.659574 (-1465 4310);
PAINT MONO (-1465 4310);
DISPLAY INVISIBLE (-1465 4310);
FORCEPROP 1 LASTPIN (-1475 4300) BN 3
J 0
(-1487 4308);
DISPLAY 0.680851 (-1487 4308);
PAINT GREEN (-1487 4308);
FORCEPROP 2 LAST CDS_LIB standard
J 0
(-1425 4300);
DISPLAY INVISIBLE (-1425 4300);
FORCEPROP 1 LAST BODY_TYPE PLUMBING
J 0
(-1425 4350);
DISPLAY 0.872340 (-1425 4350);
PAINT GREEN (-1425 4350);
DISPLAY INVISIBLE (-1425 4350);
FORCEPROP 1 LAST HDL_TAP TRUE
J 0
(-1100 4175);
DISPLAY 0.872340 (-1100 4175);
DISPLAY INVISIBLE (-1100 4175);
FORCEPROP 1 LAST PATH I131
J 0
(-1427 4300);
DISPLAY 0.872340 (-1427 4300);
PAINT GREEN (-1427 4300);
DISPLAY INVISIBLE (-1427 4300);
FORCEADD TAP..1
(-1425 4650);
FORCEPROP 3 LASTPIN (-1475 4650) SIG_NAME P5E_CPU1_P1_TX_BUF_DN<4>
J 0
(-1465 4660);
DISPLAY 0.659574 (-1465 4660);
PAINT MONO (-1465 4660);
DISPLAY INVISIBLE (-1465 4660);
FORCEPROP 1 LASTPIN (-1475 4650) BN 4
J 0
(-1487 4658);
DISPLAY 0.680851 (-1487 4658);
PAINT GREEN (-1487 4658);
FORCEPROP 2 LAST CDS_LIB standard
J 0
(-1425 4650);
DISPLAY INVISIBLE (-1425 4650);
FORCEPROP 1 LAST BODY_TYPE PLUMBING
J 0
(-1425 4700);
DISPLAY 0.872340 (-1425 4700);
PAINT GREEN (-1425 4700);
DISPLAY INVISIBLE (-1425 4700);
FORCEPROP 1 LAST HDL_TAP TRUE
J 0
(-1100 4525);
DISPLAY 0.872340 (-1100 4525);
DISPLAY INVISIBLE (-1100 4525);
FORCEPROP 1 LAST PATH I132
J 0
(-1427 4650);
DISPLAY 0.872340 (-1427 4650);
PAINT GREEN (-1427 4650);
DISPLAY INVISIBLE (-1427 4650);
FORCEADD TAP..1
(-1625 4750);
FORCEPROP 3 LASTPIN (-1675 4750) SIG_NAME P5E_CPU1_P1_TX_BUF_DP<4>
J 0
(-1665 4760);
DISPLAY 0.659574 (-1665 4760);
PAINT MONO (-1665 4760);
DISPLAY INVISIBLE (-1665 4760);
FORCEPROP 1 LASTPIN (-1675 4750) BN 4
J 0
(-1687 4758);
DISPLAY 0.680851 (-1687 4758);
PAINT GREEN (-1687 4758);
FORCEPROP 2 LAST CDS_LIB standard
J 0
(-1625 4750);
DISPLAY INVISIBLE (-1625 4750);
FORCEPROP 1 LAST BODY_TYPE PLUMBING
J 0
(-1625 4800);
DISPLAY 0.872340 (-1625 4800);
PAINT GREEN (-1625 4800);
DISPLAY INVISIBLE (-1625 4800);
FORCEPROP 1 LAST HDL_TAP TRUE
J 0
(-1300 4625);
DISPLAY 0.872340 (-1300 4625);
DISPLAY INVISIBLE (-1300 4625);
FORCEPROP 1 LAST PATH I133
J 0
(-1627 4750);
DISPLAY 0.872340 (-1627 4750);
PAINT GREEN (-1627 4750);
DISPLAY INVISIBLE (-1627 4750);
FORCEADD TAP..1
(-1625 5100);
FORCEPROP 3 LASTPIN (-1675 5100) SIG_NAME P5E_CPU1_P1_TX_BUF_DP<5>
J 0
(-1665 5110);
DISPLAY 0.659574 (-1665 5110);
PAINT MONO (-1665 5110);
DISPLAY INVISIBLE (-1665 5110);
FORCEPROP 1 LASTPIN (-1675 5100) BN 5
J 0
(-1687 5108);
DISPLAY 0.680851 (-1687 5108);
PAINT GREEN (-1687 5108);
FORCEPROP 2 LAST CDS_LIB standard
J 0
(-1625 5100);
DISPLAY INVISIBLE (-1625 5100);
FORCEPROP 1 LAST BODY_TYPE PLUMBING
J 0
(-1625 5150);
DISPLAY 0.872340 (-1625 5150);
PAINT GREEN (-1625 5150);
DISPLAY INVISIBLE (-1625 5150);
FORCEPROP 1 LAST HDL_TAP TRUE
J 0
(-1300 4975);
DISPLAY 0.872340 (-1300 4975);
DISPLAY INVISIBLE (-1300 4975);
FORCEPROP 1 LAST PATH I134
J 0
(-1627 5100);
DISPLAY 0.872340 (-1627 5100);
PAINT GREEN (-1627 5100);
DISPLAY INVISIBLE (-1627 5100);
FORCEADD TAP..1
(-1425 5000);
FORCEPROP 3 LASTPIN (-1475 5000) SIG_NAME P5E_CPU1_P1_TX_BUF_DN<5>
J 0
(-1465 5010);
DISPLAY 0.659574 (-1465 5010);
PAINT MONO (-1465 5010);
DISPLAY INVISIBLE (-1465 5010);
FORCEPROP 1 LASTPIN (-1475 5000) BN 5
J 0
(-1487 5008);
DISPLAY 0.680851 (-1487 5008);
PAINT GREEN (-1487 5008);
FORCEPROP 2 LAST CDS_LIB standard
J 0
(-1425 5000);
DISPLAY INVISIBLE (-1425 5000);
FORCEPROP 1 LAST BODY_TYPE PLUMBING
J 0
(-1425 5050);
DISPLAY 0.872340 (-1425 5050);
PAINT GREEN (-1425 5050);
DISPLAY INVISIBLE (-1425 5050);
FORCEPROP 1 LAST HDL_TAP TRUE
J 0
(-1100 4875);
DISPLAY 0.872340 (-1100 4875);
DISPLAY INVISIBLE (-1100 4875);
FORCEPROP 1 LAST PATH I135
J 0
(-1427 5000);
DISPLAY 0.872340 (-1427 5000);
PAINT GREEN (-1427 5000);
DISPLAY INVISIBLE (-1427 5000);
FORCEADD TAP..1
(-1625 5450);
FORCEPROP 3 LASTPIN (-1675 5450) SIG_NAME P5E_CPU1_P1_TX_BUF_DP<6>
J 0
(-1665 5460);
DISPLAY 0.659574 (-1665 5460);
PAINT MONO (-1665 5460);
DISPLAY INVISIBLE (-1665 5460);
FORCEPROP 1 LASTPIN (-1675 5450) BN 6
J 0
(-1687 5458);
DISPLAY 0.680851 (-1687 5458);
PAINT GREEN (-1687 5458);
FORCEPROP 2 LAST CDS_LIB standard
J 0
(-1625 5450);
DISPLAY INVISIBLE (-1625 5450);
FORCEPROP 1 LAST BODY_TYPE PLUMBING
J 0
(-1625 5500);
DISPLAY 0.872340 (-1625 5500);
PAINT GREEN (-1625 5500);
DISPLAY INVISIBLE (-1625 5500);
FORCEPROP 1 LAST HDL_TAP TRUE
J 0
(-1300 5325);
DISPLAY 0.872340 (-1300 5325);
DISPLAY INVISIBLE (-1300 5325);
FORCEPROP 1 LAST PATH I136
J 0
(-1627 5450);
DISPLAY 0.872340 (-1627 5450);
PAINT GREEN (-1627 5450);
DISPLAY INVISIBLE (-1627 5450);
FORCEADD TAP..1
(-1425 5350);
FORCEPROP 3 LASTPIN (-1475 5350) SIG_NAME P5E_CPU1_P1_TX_BUF_DN<6>
J 0
(-1465 5360);
DISPLAY 0.659574 (-1465 5360);
PAINT MONO (-1465 5360);
DISPLAY INVISIBLE (-1465 5360);
FORCEPROP 1 LASTPIN (-1475 5350) BN 6
J 0
(-1487 5358);
DISPLAY 0.680851 (-1487 5358);
PAINT GREEN (-1487 5358);
FORCEPROP 2 LAST CDS_LIB standard
J 0
(-1425 5350);
DISPLAY INVISIBLE (-1425 5350);
FORCEPROP 1 LAST BODY_TYPE PLUMBING
J 0
(-1425 5400);
DISPLAY 0.872340 (-1425 5400);
PAINT GREEN (-1425 5400);
DISPLAY INVISIBLE (-1425 5400);
FORCEPROP 1 LAST HDL_TAP TRUE
J 0
(-1100 5225);
DISPLAY 0.872340 (-1100 5225);
DISPLAY INVISIBLE (-1100 5225);
FORCEPROP 1 LAST PATH I137
J 0
(-1427 5350);
DISPLAY 0.872340 (-1427 5350);
PAINT GREEN (-1427 5350);
DISPLAY INVISIBLE (-1427 5350);
FORCEADD TAP..1
(-1425 5700);
FORCEPROP 3 LASTPIN (-1475 5700) SIG_NAME P5E_CPU1_P1_TX_BUF_DN<7>
J 0
(-1465 5710);
DISPLAY 0.659574 (-1465 5710);
PAINT MONO (-1465 5710);
DISPLAY INVISIBLE (-1465 5710);
FORCEPROP 1 LASTPIN (-1475 5700) BN 7
J 0
(-1487 5708);
DISPLAY 0.680851 (-1487 5708);
PAINT GREEN (-1487 5708);
FORCEPROP 2 LAST CDS_LIB standard
J 0
(-1425 5700);
DISPLAY INVISIBLE (-1425 5700);
FORCEPROP 1 LAST BODY_TYPE PLUMBING
J 0
(-1425 5750);
DISPLAY 0.872340 (-1425 5750);
PAINT GREEN (-1425 5750);
DISPLAY INVISIBLE (-1425 5750);
FORCEPROP 1 LAST HDL_TAP TRUE
J 0
(-1100 5575);
DISPLAY 0.872340 (-1100 5575);
DISPLAY INVISIBLE (-1100 5575);
FORCEPROP 1 LAST PATH I138
J 0
(-1427 5700);
DISPLAY 0.872340 (-1427 5700);
PAINT GREEN (-1427 5700);
DISPLAY INVISIBLE (-1427 5700);
FORCEADD TAP..1
(-1625 5800);
FORCEPROP 3 LASTPIN (-1675 5800) SIG_NAME P5E_CPU1_P1_TX_BUF_DP<7>
J 0
(-1665 5810);
DISPLAY 0.659574 (-1665 5810);
PAINT MONO (-1665 5810);
DISPLAY INVISIBLE (-1665 5810);
FORCEPROP 1 LASTPIN (-1675 5800) BN 7
J 0
(-1687 5808);
DISPLAY 0.680851 (-1687 5808);
PAINT GREEN (-1687 5808);
FORCEPROP 2 LAST CDS_LIB standard
J 0
(-1625 5800);
DISPLAY INVISIBLE (-1625 5800);
FORCEPROP 1 LAST BODY_TYPE PLUMBING
J 0
(-1625 5850);
DISPLAY 0.872340 (-1625 5850);
PAINT GREEN (-1625 5850);
DISPLAY INVISIBLE (-1625 5850);
FORCEPROP 1 LAST HDL_TAP TRUE
J 0
(-1300 5675);
DISPLAY 0.872340 (-1300 5675);
DISPLAY INVISIBLE (-1300 5675);
FORCEPROP 1 LAST PATH I139
J 0
(-1627 5800);
DISPLAY 0.872340 (-1627 5800);
PAINT GREEN (-1627 5800);
DISPLAY INVISIBLE (-1627 5800);
FORCEADD TAP..1
R 2
(-3100 1600);
FORCEPROP 3 LASTPIN (-3050 1600) SIG_NAME P5E_CPU1_P1_TX_BUF_DP<3>
J 0
(-3040 1610);
DISPLAY 0.659574 (-3040 1610);
PAINT MONO (-3040 1610);
DISPLAY INVISIBLE (-3040 1610);
FORCEPROP 1 LASTPIN (-3050 1600) BN 3
J 2
(-3038 1608);
DISPLAY 0.680851 (-3038 1608);
PAINT GREEN (-3038 1608);
FORCEPROP 2 LAST CDS_LIB standard
J 0
(-3100 1600);
DISPLAY INVISIBLE (-3100 1600);
FORCEPROP 1 LAST BODY_TYPE PLUMBING
J 2
(-3100 1650);
DISPLAY 0.872340 (-3100 1650);
PAINT GREEN (-3100 1650);
DISPLAY INVISIBLE (-3100 1650);
FORCEPROP 1 LAST HDL_TAP TRUE
J 2
(-3425 1475);
DISPLAY 0.872340 (-3425 1475);
DISPLAY INVISIBLE (-3425 1475);
FORCEPROP 1 LAST PATH I14
J 2
(-3098 1600);
DISPLAY 0.872340 (-3098 1600);
PAINT GREEN (-3098 1600);
DISPLAY INVISIBLE (-3098 1600);
FORCEADD OFFPAGE..5
R 2
(-450 5725);
FORCEPROP 2 LAST $XR0 331 
J 0
(-261 5725);
DISPLAY 0.638298 (-261 5725);
PAINT MONO (-261 5725);
FORCEPROP 2 LAST CDS_LIB standard
J 0
(-450 5725);
DISPLAY INVISIBLE (-450 5725);
FORCEPROP 1 LAST OFFPAGE TRUE
J 2
(-775 5600);
DISPLAY 0.872340 (-775 5600);
PAINT GREEN (-775 5600);
DISPLAY INVISIBLE (-775 5600);
FORCEPROP 1 LAST COMMENT_BODY TRUE
J 2
(-550 5650);
DISPLAY 0.872340 (-550 5650);
PAINT GREEN (-550 5650);
DISPLAY INVISIBLE (-550 5650);
FORCEPROP 2 LAST PATH I140
J 0
(-275 5800);
DISPLAY 0.680851 (-275 5800);
DISPLAY INVISIBLE (-275 5800);
FORCEADD OFFPAGE..5
R 2
(-425 5825);
FORCEPROP 2 LAST $XR0 331 
J 0
(-236 5825);
DISPLAY 0.638298 (-236 5825);
PAINT MONO (-236 5825);
FORCEPROP 2 LAST CDS_LIB standard
J 0
(-425 5825);
DISPLAY INVISIBLE (-425 5825);
FORCEPROP 1 LAST OFFPAGE TRUE
J 2
(-750 5700);
DISPLAY 0.872340 (-750 5700);
PAINT GREEN (-750 5700);
DISPLAY INVISIBLE (-750 5700);
FORCEPROP 1 LAST COMMENT_BODY TRUE
J 2
(-525 5750);
DISPLAY 0.872340 (-525 5750);
PAINT GREEN (-525 5750);
DISPLAY INVISIBLE (-525 5750);
FORCEPROP 2 LAST PATH I141
J 0
(-250 5900);
DISPLAY 0.680851 (-250 5900);
DISPLAY INVISIBLE (-250 5900);
FORCEADD PT5161LRS..11
(-2350 4550);
FORCEPROP 1 LAST LOCATION U6015
J 0
(-2700 6175);
DISPLAY 0.723404 (-2700 6175);
PAINT GREEN (-2700 6175);
FORCEPROP 0 LAST $SEC 11
J 0
(-2700 6325);
DISPLAY 0.680851 (-2700 6325);
PAINT MONO (-2700 6325);
DISPLAY INVISIBLE (-2700 6325);
FORCEPROP 0 LAST CDS_SEC 11
J 0
(-2700 6325);
DISPLAY 0.680851 (-2700 6325);
DISPLAY INVISIBLE (-2700 6325);
FORCEPROP 0 LASTPIN (-1900 5700) $PN CK10
J 0
(-1890 5710);
DISPLAY 0.680851 (-1890 5710);
PAINT MONO (-1890 5710);
FORCEPROP 0 LASTPIN (-1900 5350) $PN CU10
J 0
(-1890 5360);
DISPLAY 0.680851 (-1890 5360);
PAINT MONO (-1890 5360);
FORCEPROP 0 LASTPIN (-1900 5000) $PN DD10
J 0
(-1890 5010);
DISPLAY 0.680851 (-1890 5010);
PAINT MONO (-1890 5010);
FORCEPROP 0 LASTPIN (-1900 4650) $PN DL10
J 0
(-1890 4660);
DISPLAY 0.680851 (-1890 4660);
PAINT MONO (-1890 4660);
FORCEPROP 0 LASTPIN (-1900 4300) $PN DV10
J 0
(-1890 4310);
DISPLAY 0.680851 (-1890 4310);
PAINT MONO (-1890 4310);
FORCEPROP 0 LASTPIN (-1900 3950) $PN EE10
J 0
(-1890 3960);
DISPLAY 0.680851 (-1890 3960);
PAINT MONO (-1890 3960);
FORCEPROP 0 LASTPIN (-1900 3600) $PN EM10
J 0
(-1890 3610);
DISPLAY 0.680851 (-1890 3610);
PAINT MONO (-1890 3610);
FORCEPROP 0 LASTPIN (-1900 3250) $PN EW10
J 0
(-1890 3260);
DISPLAY 0.680851 (-1890 3260);
PAINT MONO (-1890 3260);
FORCEPROP 0 LASTPIN (-1900 5800) $PN CH7
J 0
(-1890 5810);
DISPLAY 0.680851 (-1890 5810);
PAINT MONO (-1890 5810);
FORCEPROP 0 LASTPIN (-1900 5450) $PN CR7
J 0
(-1890 5460);
DISPLAY 0.680851 (-1890 5460);
PAINT MONO (-1890 5460);
FORCEPROP 0 LASTPIN (-1900 5100) $PN DB7
J 0
(-1890 5110);
DISPLAY 0.680851 (-1890 5110);
PAINT MONO (-1890 5110);
FORCEPROP 0 LASTPIN (-1900 4750) $PN DJ7
J 0
(-1890 4760);
DISPLAY 0.680851 (-1890 4760);
PAINT MONO (-1890 4760);
FORCEPROP 0 LASTPIN (-1900 4400) $PN DT7
J 0
(-1890 4410);
DISPLAY 0.680851 (-1890 4410);
PAINT MONO (-1890 4410);
FORCEPROP 0 LASTPIN (-1900 4050) $PN EC7
J 0
(-1890 4060);
DISPLAY 0.680851 (-1890 4060);
PAINT MONO (-1890 4060);
FORCEPROP 0 LASTPIN (-1900 3700) $PN EK7
J 0
(-1890 3710);
DISPLAY 0.680851 (-1890 3710);
PAINT MONO (-1890 3710);
FORCEPROP 0 LASTPIN (-1900 3350) $PN EU7
J 0
(-1890 3360);
DISPLAY 0.680851 (-1890 3360);
PAINT MONO (-1890 3360);
FORCEPROP 2 LAST PART_TYPE SMLF
J 0
(-2700 6275);
DISPLAY 0.680851 (-2700 6275);
FORCEPROP 2 LAST VALUE PT5161LRS
J 0
(-2700 6225);
DISPLAY 0.680851 (-2700 6225);
FORCEPROP 1 LAST MATERIAL IC
J 0
(-2700 6025);
DISPLAY 0.723404 (-2700 6025);
PAINT GREEN (-2700 6025);
FORCEPROP 2 LAST CDS_LIB pure_quanta
J 0
(-2350 4550);
DISPLAY INVISIBLE (-2350 4550);
FORCEPROP 1 LAST CDS_LMAN_SYM_OUTLINE -350,1450,300,-1400
J 0
(-2350 4550);
DISPLAY 0.468085 (-2350 4550);
PAINT GREEN (-2350 4550);
DISPLAY INVISIBLE (-2350 4550);
FORCEPROP 1 LAST NEEDS_NO_SIZE TRUE
J 0
(-2350 4550);
DISPLAY 0.723404 (-2350 4550);
PAINT GREEN (-2350 4550);
DISPLAY INVISIBLE (-2350 4550);
FORCEPROP 1 LAST PATH I142
J 0
(-2350 4550);
DISPLAY 0.723404 (-2350 4550);
PAINT GREEN (-2350 4550);
DISPLAY INVISIBLE (-2350 4550);
FORCEPROP 1 LAST PART_NUMBER AJ051610U03
J 0
(-2700 6100);
DISPLAY 0.723404 (-2700 6100);
PAINT GREEN (-2700 6100);
DISPLAY INVISIBLE (-2700 6100);
FORCEADD TAP..1
R 2
(-3100 1800);
FORCEPROP 3 LASTPIN (-3050 1800) SIG_NAME P5E_CPU1_P1_TX_BUF_DP<2>
J 0
(-3040 1810);
DISPLAY 0.659574 (-3040 1810);
PAINT MONO (-3040 1810);
DISPLAY INVISIBLE (-3040 1810);
FORCEPROP 1 LASTPIN (-3050 1800) BN 2
J 2
(-3038 1808);
DISPLAY 0.680851 (-3038 1808);
PAINT GREEN (-3038 1808);
FORCEPROP 2 LAST CDS_LIB standard
J 0
(-3100 1800);
DISPLAY INVISIBLE (-3100 1800);
FORCEPROP 1 LAST BODY_TYPE PLUMBING
J 2
(-3100 1850);
DISPLAY 0.872340 (-3100 1850);
PAINT GREEN (-3100 1850);
DISPLAY INVISIBLE (-3100 1850);
FORCEPROP 1 LAST HDL_TAP TRUE
J 2
(-3425 1675);
DISPLAY 0.872340 (-3425 1675);
DISPLAY INVISIBLE (-3425 1675);
FORCEPROP 1 LAST PATH I15
J 2
(-3098 1800);
DISPLAY 0.872340 (-3098 1800);
PAINT GREEN (-3098 1800);
DISPLAY INVISIBLE (-3098 1800);
FORCEADD TAP..1
R 2
(-3100 2000);
FORCEPROP 3 LASTPIN (-3050 2000) SIG_NAME P5E_CPU1_P1_TX_BUF_DP<1>
J 0
(-3040 2010);
DISPLAY 0.659574 (-3040 2010);
PAINT MONO (-3040 2010);
DISPLAY INVISIBLE (-3040 2010);
FORCEPROP 1 LASTPIN (-3050 2000) BN 1
J 2
(-3038 2008);
DISPLAY 0.680851 (-3038 2008);
PAINT GREEN (-3038 2008);
FORCEPROP 2 LAST CDS_LIB standard
J 0
(-3100 2000);
DISPLAY INVISIBLE (-3100 2000);
FORCEPROP 1 LAST BODY_TYPE PLUMBING
J 2
(-3100 2050);
DISPLAY 0.872340 (-3100 2050);
PAINT GREEN (-3100 2050);
DISPLAY INVISIBLE (-3100 2050);
FORCEPROP 1 LAST HDL_TAP TRUE
J 2
(-3425 1875);
DISPLAY 0.872340 (-3425 1875);
DISPLAY INVISIBLE (-3425 1875);
FORCEPROP 1 LAST PATH I16
J 2
(-3098 2000);
DISPLAY 0.872340 (-3098 2000);
PAINT GREEN (-3098 2000);
DISPLAY INVISIBLE (-3098 2000);
FORCEADD Q_CAP_DIFFBUS..2
R 2
(-2375 750);
FORCEPROP 1 LAST LOCATION C6676
J 2
(-2100 750);
DISPLAY 0.723404 (-2100 750);
PAINT GREEN (-2100 750);
FORCEPROP 2 LAST $SEC 1
J 2
(-2200 825);
DISPLAY 0.680851 (-2200 825);
PAINT MONO (-2200 825);
DISPLAY INVISIBLE (-2200 825);
FORCEPROP 2 LAST CDS_SEC 1
J 2
(-2200 825);
DISPLAY 0.680851 (-2200 825);
DISPLAY INVISIBLE (-2200 825);
FORCEPROP 2 LASTPIN (-2300 750) $PN 1
J 0
(-2290 760);
DISPLAY 0.808511 (-2290 760);
FORCEPROP 2 LASTPIN (-2450 750) $PN 2
J 2
(-2460 760);
DISPLAY 0.808511 (-2460 760);
FORCEPROP 2 LAST VALUE DIFF BUS_0.22UF
J 2
(-2525 750);
DISPLAY 0.553191 (-2525 750);
FORCEPROP 1 LAST CDS_LMAN_SYM_OUTLINE -25,50,25,-50
J 2
(-2375 750);
DISPLAY 0.468085 (-2375 750);
PAINT GREEN (-2375 750);
DISPLAY INVISIBLE (-2375 750);
FORCEPROP 2 LAST CDS_LIB pure_quanta
J 2
(-2375 750);
DISPLAY INVISIBLE (-2375 750);
FORCEPROP 1 LAST PIN_NAMES_ROTATE TRUE
J 2
(-2375 750);
DISPLAY 0.489362 (-2375 750);
PAINT GREEN (-2375 750);
DISPLAY INVISIBLE (-2375 750);
FORCEPROP 2 LAST VOLTAGE 6.3V
J 2
(-2725 800);
DISPLAY 0.553191 (-2725 800);
DISPLAY INVISIBLE (-2725 800);
FORCEPROP 1 LAST MATERIAL X6S
J 2
(-2366 829);
DISPLAY 0.574468 (-2366 829);
PAINT GREEN (-2366 829);
DISPLAY INVISIBLE (-2366 829);
FORCEPROP 2 LAST PACK_TYPE C0201
J 2
(-2550 800);
DISPLAY 0.553191 (-2550 800);
DISPLAY INVISIBLE (-2550 800);
FORCEPROP 2 LAST TOLERANCE 20%
J 2
(-2450 800);
DISPLAY 0.553191 (-2450 800);
DISPLAY INVISIBLE (-2450 800);
FORCEPROP 1 LAST PATH I17
J 2
(-2375 750);
DISPLAY 0.723404 (-2375 750);
DISPLAY INVISIBLE (-2375 750);
FORCEPROP 1 LAST PART_NUMBER SP_CH4221MEE01
J 2
(-2491 838);
DISPLAY 0.574468 (-2491 838);
PAINT GREEN (-2491 838);
DISPLAY INVISIBLE (-2491 838);
FORCEPROP 1 LAST LOCATION C6676
J 0
(-2125 825);
DISPLAY 1.021277 (-2125 825);
DISPLAY INVISIBLE (-2125 825);
FORCEADD Q_CAP_DIFFBUS..2
R 2
(-2375 800);
FORCEPROP 1 LAST LOCATION C6675
J 2
(-2100 800);
DISPLAY 0.723404 (-2100 800);
PAINT GREEN (-2100 800);
FORCEPROP 2 LAST $SEC 1
J 2
(-2200 875);
DISPLAY 0.680851 (-2200 875);
PAINT MONO (-2200 875);
DISPLAY INVISIBLE (-2200 875);
FORCEPROP 2 LAST CDS_SEC 1
J 2
(-2200 875);
DISPLAY 0.680851 (-2200 875);
DISPLAY INVISIBLE (-2200 875);
FORCEPROP 2 LASTPIN (-2300 800) $PN 1
J 0
(-2290 810);
DISPLAY 0.808511 (-2290 810);
FORCEPROP 2 LASTPIN (-2450 800) $PN 2
J 2
(-2460 810);
DISPLAY 0.808511 (-2460 810);
FORCEPROP 2 LAST VALUE DIFF BUS_0.22UF
J 2
(-2525 800);
DISPLAY 0.553191 (-2525 800);
FORCEPROP 1 LAST CDS_LMAN_SYM_OUTLINE -25,50,25,-50
J 2
(-2375 800);
DISPLAY 0.468085 (-2375 800);
PAINT GREEN (-2375 800);
DISPLAY INVISIBLE (-2375 800);
FORCEPROP 2 LAST CDS_LIB pure_quanta
J 2
(-2375 800);
DISPLAY INVISIBLE (-2375 800);
FORCEPROP 1 LAST PIN_NAMES_ROTATE TRUE
J 2
(-2375 800);
DISPLAY 0.489362 (-2375 800);
PAINT GREEN (-2375 800);
DISPLAY INVISIBLE (-2375 800);
FORCEPROP 2 LAST VOLTAGE 6.3V
J 2
(-2725 850);
DISPLAY 0.553191 (-2725 850);
DISPLAY INVISIBLE (-2725 850);
FORCEPROP 1 LAST MATERIAL X6S
J 2
(-2366 879);
DISPLAY 0.574468 (-2366 879);
PAINT GREEN (-2366 879);
DISPLAY INVISIBLE (-2366 879);
FORCEPROP 2 LAST PACK_TYPE C0201
J 2
(-2550 850);
DISPLAY 0.553191 (-2550 850);
DISPLAY INVISIBLE (-2550 850);
FORCEPROP 2 LAST TOLERANCE 20%
J 2
(-2450 850);
DISPLAY 0.553191 (-2450 850);
DISPLAY INVISIBLE (-2450 850);
FORCEPROP 1 LAST PATH I18
J 2
(-2375 800);
DISPLAY 0.723404 (-2375 800);
DISPLAY INVISIBLE (-2375 800);
FORCEPROP 1 LAST PART_NUMBER SP_CH4221MEE01
J 2
(-2491 888);
DISPLAY 0.574468 (-2491 888);
PAINT GREEN (-2491 888);
DISPLAY INVISIBLE (-2491 888);
FORCEPROP 1 LAST LOCATION C6675
J 0
(-2125 875);
DISPLAY 1.021277 (-2125 875);
DISPLAY INVISIBLE (-2125 875);
FORCEADD Q_CAP_DIFFBUS..2
R 2
(-2375 950);
FORCEPROP 1 LAST LOCATION C6674
J 2
(-2100 950);
DISPLAY 0.723404 (-2100 950);
PAINT GREEN (-2100 950);
FORCEPROP 2 LAST $SEC 1
J 2
(-2200 1025);
DISPLAY 0.680851 (-2200 1025);
PAINT MONO (-2200 1025);
DISPLAY INVISIBLE (-2200 1025);
FORCEPROP 2 LAST CDS_SEC 1
J 2
(-2200 1025);
DISPLAY 0.680851 (-2200 1025);
DISPLAY INVISIBLE (-2200 1025);
FORCEPROP 2 LASTPIN (-2300 950) $PN 1
J 0
(-2290 960);
DISPLAY 0.808511 (-2290 960);
FORCEPROP 2 LASTPIN (-2450 950) $PN 2
J 2
(-2460 960);
DISPLAY 0.808511 (-2460 960);
FORCEPROP 2 LAST VALUE DIFF BUS_0.22UF
J 2
(-2525 950);
DISPLAY 0.553191 (-2525 950);
FORCEPROP 1 LAST CDS_LMAN_SYM_OUTLINE -25,50,25,-50
J 2
(-2375 950);
DISPLAY 0.468085 (-2375 950);
PAINT GREEN (-2375 950);
DISPLAY INVISIBLE (-2375 950);
FORCEPROP 2 LAST CDS_LIB pure_quanta
J 2
(-2375 950);
DISPLAY INVISIBLE (-2375 950);
FORCEPROP 1 LAST PIN_NAMES_ROTATE TRUE
J 2
(-2375 950);
DISPLAY 0.489362 (-2375 950);
PAINT GREEN (-2375 950);
DISPLAY INVISIBLE (-2375 950);
FORCEPROP 2 LAST VOLTAGE 6.3V
J 2
(-2725 1000);
DISPLAY 0.553191 (-2725 1000);
DISPLAY INVISIBLE (-2725 1000);
FORCEPROP 1 LAST MATERIAL X6S
J 2
(-2366 1029);
DISPLAY 0.574468 (-2366 1029);
PAINT GREEN (-2366 1029);
DISPLAY INVISIBLE (-2366 1029);
FORCEPROP 2 LAST PACK_TYPE C0201
J 2
(-2550 1000);
DISPLAY 0.553191 (-2550 1000);
DISPLAY INVISIBLE (-2550 1000);
FORCEPROP 2 LAST TOLERANCE 20%
J 2
(-2450 1000);
DISPLAY 0.553191 (-2450 1000);
DISPLAY INVISIBLE (-2450 1000);
FORCEPROP 1 LAST PATH I19
J 2
(-2375 950);
DISPLAY 0.723404 (-2375 950);
DISPLAY INVISIBLE (-2375 950);
FORCEPROP 1 LAST PART_NUMBER SP_CH4221MEE01
J 2
(-2491 1038);
DISPLAY 0.574468 (-2491 1038);
PAINT GREEN (-2491 1038);
DISPLAY INVISIBLE (-2491 1038);
FORCEPROP 1 LAST LOCATION C6674
J 0
(-2125 1025);
DISPLAY 1.021277 (-2125 1025);
DISPLAY INVISIBLE (-2125 1025);
FORCEADD OFFPAGE..1
(-4300 2225);
FORCEPROP 2 LAST $XR0 331 
J 0
(-4552 2225);
DISPLAY 0.638298 (-4552 2225);
PAINT MONO (-4552 2225);
FORCEPROP 2 LAST CDS_LIB standard
J 0
(-4300 2225);
DISPLAY INVISIBLE (-4300 2225);
FORCEPROP 1 LAST OFFPAGE TRUE
J 0
(-3975 2100);
DISPLAY 0.872340 (-3975 2100);
DISPLAY INVISIBLE (-3975 2100);
FORCEPROP 1 LAST COMMENT_BODY TRUE
J 0
(-4175 2125);
DISPLAY 0.872340 (-4175 2125);
PAINT GREEN (-4175 2125);
DISPLAY INVISIBLE (-4175 2125);
FORCEPROP 2 LAST PATH I2
J 0
(-4550 2275);
DISPLAY 0.680851 (-4550 2275);
DISPLAY INVISIBLE (-4550 2275);
FORCEADD Q_CAP_DIFFBUS..2
R 2
(-2375 1000);
FORCEPROP 1 LAST LOCATION C6673
J 2
(-2100 1000);
DISPLAY 0.723404 (-2100 1000);
PAINT GREEN (-2100 1000);
FORCEPROP 2 LAST $SEC 1
J 2
(-2200 1075);
DISPLAY 0.680851 (-2200 1075);
PAINT MONO (-2200 1075);
DISPLAY INVISIBLE (-2200 1075);
FORCEPROP 2 LAST CDS_SEC 1
J 2
(-2200 1075);
DISPLAY 0.680851 (-2200 1075);
DISPLAY INVISIBLE (-2200 1075);
FORCEPROP 2 LASTPIN (-2300 1000) $PN 1
J 0
(-2290 1010);
DISPLAY 0.808511 (-2290 1010);
FORCEPROP 2 LASTPIN (-2450 1000) $PN 2
J 2
(-2460 1010);
DISPLAY 0.808511 (-2460 1010);
FORCEPROP 2 LAST VALUE DIFF BUS_0.22UF
J 2
(-2525 1000);
DISPLAY 0.553191 (-2525 1000);
FORCEPROP 2 LAST CDS_LIB pure_quanta
J 2
(-2375 1000);
DISPLAY INVISIBLE (-2375 1000);
FORCEPROP 1 LAST CDS_LMAN_SYM_OUTLINE -25,50,25,-50
J 2
(-2375 1000);
DISPLAY 0.468085 (-2375 1000);
PAINT GREEN (-2375 1000);
DISPLAY INVISIBLE (-2375 1000);
FORCEPROP 1 LAST PIN_NAMES_ROTATE TRUE
J 2
(-2375 1000);
DISPLAY 0.489362 (-2375 1000);
PAINT GREEN (-2375 1000);
DISPLAY INVISIBLE (-2375 1000);
FORCEPROP 2 LAST VOLTAGE 6.3V
J 2
(-2725 1050);
DISPLAY 0.553191 (-2725 1050);
DISPLAY INVISIBLE (-2725 1050);
FORCEPROP 1 LAST MATERIAL X6S
J 2
(-2366 1079);
DISPLAY 0.574468 (-2366 1079);
PAINT GREEN (-2366 1079);
DISPLAY INVISIBLE (-2366 1079);
FORCEPROP 2 LAST PACK_TYPE C0201
J 2
(-2550 1050);
DISPLAY 0.553191 (-2550 1050);
DISPLAY INVISIBLE (-2550 1050);
FORCEPROP 2 LAST TOLERANCE 20%
J 2
(-2450 1050);
DISPLAY 0.553191 (-2450 1050);
DISPLAY INVISIBLE (-2450 1050);
FORCEPROP 1 LAST PATH I20
J 2
(-2375 1000);
DISPLAY 0.723404 (-2375 1000);
DISPLAY INVISIBLE (-2375 1000);
FORCEPROP 1 LAST PART_NUMBER SP_CH4221MEE01
J 2
(-2491 1088);
DISPLAY 0.574468 (-2491 1088);
PAINT GREEN (-2491 1088);
DISPLAY INVISIBLE (-2491 1088);
FORCEPROP 1 LAST LOCATION C6673
J 0
(-2125 1075);
DISPLAY 1.021277 (-2125 1075);
DISPLAY INVISIBLE (-2125 1075);
FORCEADD TAP..1
(-1825 800);
FORCEPROP 3 LASTPIN (-1875 800) SIG_NAME P5E_CPU1_P1_TX_BUF_C_DP<7>
J 0
(-1865 810);
DISPLAY 0.659574 (-1865 810);
PAINT MONO (-1865 810);
DISPLAY INVISIBLE (-1865 810);
FORCEPROP 1 LASTPIN (-1875 800) BN 7
J 0
(-1887 808);
DISPLAY 0.680851 (-1887 808);
PAINT GREEN (-1887 808);
FORCEPROP 2 LAST CDS_LIB standard
J 0
(-1825 800);
DISPLAY INVISIBLE (-1825 800);
FORCEPROP 1 LAST BODY_TYPE PLUMBING
J 0
(-1825 850);
DISPLAY 0.872340 (-1825 850);
PAINT GREEN (-1825 850);
DISPLAY INVISIBLE (-1825 850);
FORCEPROP 1 LAST HDL_TAP TRUE
J 0
(-1500 675);
DISPLAY 0.872340 (-1500 675);
DISPLAY INVISIBLE (-1500 675);
FORCEPROP 1 LAST PATH I21
J 0
(-1827 800);
DISPLAY 0.872340 (-1827 800);
PAINT GREEN (-1827 800);
DISPLAY INVISIBLE (-1827 800);
FORCEADD TAP..1
(-1825 1000);
FORCEPROP 3 LASTPIN (-1875 1000) SIG_NAME P5E_CPU1_P1_TX_BUF_C_DP<6>
J 0
(-1865 1010);
DISPLAY 0.659574 (-1865 1010);
PAINT MONO (-1865 1010);
DISPLAY INVISIBLE (-1865 1010);
FORCEPROP 1 LASTPIN (-1875 1000) BN 6
J 0
(-1887 1008);
DISPLAY 0.680851 (-1887 1008);
PAINT GREEN (-1887 1008);
FORCEPROP 2 LAST CDS_LIB standard
J 0
(-1825 1000);
DISPLAY INVISIBLE (-1825 1000);
FORCEPROP 1 LAST BODY_TYPE PLUMBING
J 0
(-1825 1050);
DISPLAY 0.872340 (-1825 1050);
PAINT GREEN (-1825 1050);
DISPLAY INVISIBLE (-1825 1050);
FORCEPROP 1 LAST HDL_TAP TRUE
J 0
(-1500 875);
DISPLAY 0.872340 (-1500 875);
DISPLAY INVISIBLE (-1500 875);
FORCEPROP 1 LAST PATH I22
J 0
(-1827 1000);
DISPLAY 0.872340 (-1827 1000);
PAINT GREEN (-1827 1000);
DISPLAY INVISIBLE (-1827 1000);
FORCEADD Q_CAP_DIFFBUS..2
R 2
(-2375 1150);
FORCEPROP 1 LAST LOCATION C6672
J 2
(-2100 1150);
DISPLAY 0.723404 (-2100 1150);
PAINT GREEN (-2100 1150);
FORCEPROP 2 LAST $SEC 1
J 2
(-2200 1225);
DISPLAY 0.680851 (-2200 1225);
PAINT MONO (-2200 1225);
DISPLAY INVISIBLE (-2200 1225);
FORCEPROP 2 LAST CDS_SEC 1
J 2
(-2200 1225);
DISPLAY 0.680851 (-2200 1225);
DISPLAY INVISIBLE (-2200 1225);
FORCEPROP 2 LASTPIN (-2300 1150) $PN 1
J 0
(-2290 1160);
DISPLAY 0.808511 (-2290 1160);
FORCEPROP 2 LASTPIN (-2450 1150) $PN 2
J 2
(-2460 1160);
DISPLAY 0.808511 (-2460 1160);
FORCEPROP 2 LAST VALUE DIFF BUS_0.22UF
J 2
(-2525 1150);
DISPLAY 0.553191 (-2525 1150);
FORCEPROP 1 LAST CDS_LMAN_SYM_OUTLINE -25,50,25,-50
J 2
(-2375 1150);
DISPLAY 0.468085 (-2375 1150);
PAINT GREEN (-2375 1150);
DISPLAY INVISIBLE (-2375 1150);
FORCEPROP 2 LAST CDS_LIB pure_quanta
J 2
(-2375 1150);
DISPLAY INVISIBLE (-2375 1150);
FORCEPROP 1 LAST PIN_NAMES_ROTATE TRUE
J 2
(-2375 1150);
DISPLAY 0.489362 (-2375 1150);
PAINT GREEN (-2375 1150);
DISPLAY INVISIBLE (-2375 1150);
FORCEPROP 2 LAST VOLTAGE 6.3V
J 2
(-2725 1200);
DISPLAY 0.553191 (-2725 1200);
DISPLAY INVISIBLE (-2725 1200);
FORCEPROP 1 LAST MATERIAL X6S
J 2
(-2366 1229);
DISPLAY 0.574468 (-2366 1229);
PAINT GREEN (-2366 1229);
DISPLAY INVISIBLE (-2366 1229);
FORCEPROP 2 LAST PACK_TYPE C0201
J 2
(-2550 1200);
DISPLAY 0.553191 (-2550 1200);
DISPLAY INVISIBLE (-2550 1200);
FORCEPROP 2 LAST TOLERANCE 20%
J 2
(-2450 1200);
DISPLAY 0.553191 (-2450 1200);
DISPLAY INVISIBLE (-2450 1200);
FORCEPROP 1 LAST PATH I23
J 2
(-2375 1150);
DISPLAY 0.723404 (-2375 1150);
DISPLAY INVISIBLE (-2375 1150);
FORCEPROP 1 LAST PART_NUMBER SP_CH4221MEE01
J 2
(-2491 1238);
DISPLAY 0.574468 (-2491 1238);
PAINT GREEN (-2491 1238);
DISPLAY INVISIBLE (-2491 1238);
FORCEPROP 1 LAST LOCATION C6672
J 0
(-2125 1225);
DISPLAY 1.021277 (-2125 1225);
DISPLAY INVISIBLE (-2125 1225);
FORCEADD Q_CAP_DIFFBUS..2
R 2
(-2375 1200);
FORCEPROP 1 LAST LOCATION C6671
J 2
(-2100 1200);
DISPLAY 0.723404 (-2100 1200);
PAINT GREEN (-2100 1200);
FORCEPROP 2 LAST $SEC 1
J 2
(-2200 1275);
DISPLAY 0.680851 (-2200 1275);
PAINT MONO (-2200 1275);
DISPLAY INVISIBLE (-2200 1275);
FORCEPROP 2 LAST CDS_SEC 1
J 2
(-2200 1275);
DISPLAY 0.680851 (-2200 1275);
DISPLAY INVISIBLE (-2200 1275);
FORCEPROP 2 LASTPIN (-2300 1200) $PN 1
J 0
(-2290 1210);
DISPLAY 0.808511 (-2290 1210);
FORCEPROP 2 LASTPIN (-2450 1200) $PN 2
J 2
(-2460 1210);
DISPLAY 0.808511 (-2460 1210);
FORCEPROP 2 LAST VALUE DIFF BUS_0.22UF
J 2
(-2525 1200);
DISPLAY 0.553191 (-2525 1200);
FORCEPROP 1 LAST CDS_LMAN_SYM_OUTLINE -25,50,25,-50
J 2
(-2375 1200);
DISPLAY 0.468085 (-2375 1200);
PAINT GREEN (-2375 1200);
DISPLAY INVISIBLE (-2375 1200);
FORCEPROP 2 LAST CDS_LIB pure_quanta
J 2
(-2375 1200);
DISPLAY INVISIBLE (-2375 1200);
FORCEPROP 1 LAST PIN_NAMES_ROTATE TRUE
J 2
(-2375 1200);
DISPLAY 0.489362 (-2375 1200);
PAINT GREEN (-2375 1200);
DISPLAY INVISIBLE (-2375 1200);
FORCEPROP 2 LAST VOLTAGE 6.3V
J 2
(-2725 1250);
DISPLAY 0.553191 (-2725 1250);
DISPLAY INVISIBLE (-2725 1250);
FORCEPROP 1 LAST MATERIAL X6S
J 2
(-2366 1279);
DISPLAY 0.574468 (-2366 1279);
PAINT GREEN (-2366 1279);
DISPLAY INVISIBLE (-2366 1279);
FORCEPROP 2 LAST PACK_TYPE C0201
J 2
(-2550 1250);
DISPLAY 0.553191 (-2550 1250);
DISPLAY INVISIBLE (-2550 1250);
FORCEPROP 2 LAST TOLERANCE 20%
J 2
(-2450 1250);
DISPLAY 0.553191 (-2450 1250);
DISPLAY INVISIBLE (-2450 1250);
FORCEPROP 1 LAST PATH I24
J 2
(-2375 1200);
DISPLAY 0.723404 (-2375 1200);
DISPLAY INVISIBLE (-2375 1200);
FORCEPROP 1 LAST PART_NUMBER SP_CH4221MEE01
J 2
(-2491 1288);
DISPLAY 0.574468 (-2491 1288);
PAINT GREEN (-2491 1288);
DISPLAY INVISIBLE (-2491 1288);
FORCEPROP 1 LAST LOCATION C6671
J 0
(-2125 1275);
DISPLAY 1.021277 (-2125 1275);
DISPLAY INVISIBLE (-2125 1275);
FORCEADD Q_CAP_DIFFBUS..2
R 2
(-2375 1350);
FORCEPROP 1 LAST LOCATION C6670
J 2
(-2100 1350);
DISPLAY 0.723404 (-2100 1350);
PAINT GREEN (-2100 1350);
FORCEPROP 2 LAST $SEC 1
J 2
(-2200 1425);
DISPLAY 0.680851 (-2200 1425);
PAINT MONO (-2200 1425);
DISPLAY INVISIBLE (-2200 1425);
FORCEPROP 2 LAST CDS_SEC 1
J 2
(-2200 1425);
DISPLAY 0.680851 (-2200 1425);
DISPLAY INVISIBLE (-2200 1425);
FORCEPROP 2 LASTPIN (-2300 1350) $PN 1
J 0
(-2290 1360);
DISPLAY 0.808511 (-2290 1360);
FORCEPROP 2 LASTPIN (-2450 1350) $PN 2
J 2
(-2460 1360);
DISPLAY 0.808511 (-2460 1360);
FORCEPROP 2 LAST VALUE DIFF BUS_0.22UF
J 2
(-2525 1350);
DISPLAY 0.553191 (-2525 1350);
FORCEPROP 2 LAST CDS_LIB pure_quanta
J 2
(-2375 1350);
DISPLAY INVISIBLE (-2375 1350);
FORCEPROP 1 LAST CDS_LMAN_SYM_OUTLINE -25,50,25,-50
J 2
(-2375 1350);
DISPLAY 0.468085 (-2375 1350);
PAINT GREEN (-2375 1350);
DISPLAY INVISIBLE (-2375 1350);
FORCEPROP 1 LAST PIN_NAMES_ROTATE TRUE
J 2
(-2375 1350);
DISPLAY 0.489362 (-2375 1350);
PAINT GREEN (-2375 1350);
DISPLAY INVISIBLE (-2375 1350);
FORCEPROP 2 LAST VOLTAGE 6.3V
J 2
(-2725 1400);
DISPLAY 0.553191 (-2725 1400);
DISPLAY INVISIBLE (-2725 1400);
FORCEPROP 1 LAST MATERIAL X6S
J 2
(-2366 1429);
DISPLAY 0.574468 (-2366 1429);
PAINT GREEN (-2366 1429);
DISPLAY INVISIBLE (-2366 1429);
FORCEPROP 2 LAST PACK_TYPE C0201
J 2
(-2550 1400);
DISPLAY 0.553191 (-2550 1400);
DISPLAY INVISIBLE (-2550 1400);
FORCEPROP 2 LAST TOLERANCE 20%
J 2
(-2450 1400);
DISPLAY 0.553191 (-2450 1400);
DISPLAY INVISIBLE (-2450 1400);
FORCEPROP 1 LAST PATH I25
J 2
(-2375 1350);
DISPLAY 0.723404 (-2375 1350);
DISPLAY INVISIBLE (-2375 1350);
FORCEPROP 1 LAST PART_NUMBER SP_CH4221MEE01
J 2
(-2491 1438);
DISPLAY 0.574468 (-2491 1438);
PAINT GREEN (-2491 1438);
DISPLAY INVISIBLE (-2491 1438);
FORCEPROP 1 LAST LOCATION C6670
J 0
(-2125 1425);
DISPLAY 1.021277 (-2125 1425);
DISPLAY INVISIBLE (-2125 1425);
FORCEADD Q_CAP_DIFFBUS..2
R 2
(-2375 1400);
FORCEPROP 1 LAST LOCATION C6669
J 2
(-2100 1400);
DISPLAY 0.723404 (-2100 1400);
PAINT GREEN (-2100 1400);
FORCEPROP 2 LAST $SEC 1
J 2
(-2200 1475);
DISPLAY 0.680851 (-2200 1475);
PAINT MONO (-2200 1475);
DISPLAY INVISIBLE (-2200 1475);
FORCEPROP 2 LAST CDS_SEC 1
J 2
(-2200 1475);
DISPLAY 0.680851 (-2200 1475);
DISPLAY INVISIBLE (-2200 1475);
FORCEPROP 2 LASTPIN (-2300 1400) $PN 1
J 0
(-2290 1410);
DISPLAY 0.808511 (-2290 1410);
FORCEPROP 2 LASTPIN (-2450 1400) $PN 2
J 2
(-2460 1410);
DISPLAY 0.808511 (-2460 1410);
FORCEPROP 2 LAST VALUE DIFF BUS_0.22UF
J 2
(-2525 1400);
DISPLAY 0.553191 (-2525 1400);
FORCEPROP 2 LAST CDS_LIB pure_quanta
J 2
(-2375 1400);
DISPLAY INVISIBLE (-2375 1400);
FORCEPROP 1 LAST CDS_LMAN_SYM_OUTLINE -25,50,25,-50
J 2
(-2375 1400);
DISPLAY 0.468085 (-2375 1400);
PAINT GREEN (-2375 1400);
DISPLAY INVISIBLE (-2375 1400);
FORCEPROP 1 LAST PIN_NAMES_ROTATE TRUE
J 2
(-2375 1400);
DISPLAY 0.489362 (-2375 1400);
PAINT GREEN (-2375 1400);
DISPLAY INVISIBLE (-2375 1400);
FORCEPROP 2 LAST VOLTAGE 6.3V
J 2
(-2725 1450);
DISPLAY 0.553191 (-2725 1450);
DISPLAY INVISIBLE (-2725 1450);
FORCEPROP 1 LAST MATERIAL X6S
J 2
(-2366 1479);
DISPLAY 0.574468 (-2366 1479);
PAINT GREEN (-2366 1479);
DISPLAY INVISIBLE (-2366 1479);
FORCEPROP 2 LAST PACK_TYPE C0201
J 2
(-2550 1450);
DISPLAY 0.553191 (-2550 1450);
DISPLAY INVISIBLE (-2550 1450);
FORCEPROP 2 LAST TOLERANCE 20%
J 2
(-2450 1450);
DISPLAY 0.553191 (-2450 1450);
DISPLAY INVISIBLE (-2450 1450);
FORCEPROP 1 LAST PATH I26
J 2
(-2375 1400);
DISPLAY 0.723404 (-2375 1400);
DISPLAY INVISIBLE (-2375 1400);
FORCEPROP 1 LAST PART_NUMBER SP_CH4221MEE01
J 2
(-2491 1488);
DISPLAY 0.574468 (-2491 1488);
PAINT GREEN (-2491 1488);
DISPLAY INVISIBLE (-2491 1488);
FORCEPROP 1 LAST LOCATION C6669
J 0
(-2125 1475);
DISPLAY 1.021277 (-2125 1475);
DISPLAY INVISIBLE (-2125 1475);
FORCEADD Q_CAP_DIFFBUS..2
R 2
(-2375 1600);
FORCEPROP 1 LAST LOCATION C6667
J 2
(-2100 1600);
DISPLAY 0.723404 (-2100 1600);
PAINT GREEN (-2100 1600);
FORCEPROP 2 LAST $SEC 1
J 2
(-2200 1675);
DISPLAY 0.680851 (-2200 1675);
PAINT MONO (-2200 1675);
DISPLAY INVISIBLE (-2200 1675);
FORCEPROP 2 LAST CDS_SEC 1
J 2
(-2200 1675);
DISPLAY 0.680851 (-2200 1675);
DISPLAY INVISIBLE (-2200 1675);
FORCEPROP 2 LASTPIN (-2300 1600) $PN 1
J 0
(-2290 1610);
DISPLAY 0.808511 (-2290 1610);
FORCEPROP 2 LASTPIN (-2450 1600) $PN 2
J 2
(-2460 1610);
DISPLAY 0.808511 (-2460 1610);
FORCEPROP 2 LAST VALUE DIFF BUS_0.22UF
J 2
(-2525 1600);
DISPLAY 0.553191 (-2525 1600);
FORCEPROP 1 LAST CDS_LMAN_SYM_OUTLINE -25,50,25,-50
J 2
(-2375 1600);
DISPLAY 0.468085 (-2375 1600);
PAINT GREEN (-2375 1600);
DISPLAY INVISIBLE (-2375 1600);
FORCEPROP 2 LAST CDS_LIB pure_quanta
J 2
(-2375 1600);
DISPLAY INVISIBLE (-2375 1600);
FORCEPROP 1 LAST PIN_NAMES_ROTATE TRUE
J 2
(-2375 1600);
DISPLAY 0.489362 (-2375 1600);
PAINT GREEN (-2375 1600);
DISPLAY INVISIBLE (-2375 1600);
FORCEPROP 2 LAST VOLTAGE 6.3V
J 2
(-2725 1650);
DISPLAY 0.553191 (-2725 1650);
DISPLAY INVISIBLE (-2725 1650);
FORCEPROP 1 LAST MATERIAL X6S
J 2
(-2366 1679);
DISPLAY 0.574468 (-2366 1679);
PAINT GREEN (-2366 1679);
DISPLAY INVISIBLE (-2366 1679);
FORCEPROP 2 LAST PACK_TYPE C0201
J 2
(-2550 1650);
DISPLAY 0.553191 (-2550 1650);
DISPLAY INVISIBLE (-2550 1650);
FORCEPROP 2 LAST TOLERANCE 20%
J 2
(-2450 1650);
DISPLAY 0.553191 (-2450 1650);
DISPLAY INVISIBLE (-2450 1650);
FORCEPROP 1 LAST PATH I27
J 2
(-2375 1600);
DISPLAY 0.723404 (-2375 1600);
DISPLAY INVISIBLE (-2375 1600);
FORCEPROP 1 LAST PART_NUMBER SP_CH4221MEE01
J 2
(-2491 1688);
DISPLAY 0.574468 (-2491 1688);
PAINT GREEN (-2491 1688);
DISPLAY INVISIBLE (-2491 1688);
FORCEPROP 1 LAST LOCATION C6667
J 0
(-2125 1675);
DISPLAY 1.021277 (-2125 1675);
DISPLAY INVISIBLE (-2125 1675);
FORCEADD Q_CAP_DIFFBUS..2
R 2
(-2375 1550);
FORCEPROP 1 LAST LOCATION C6668
J 2
(-2100 1550);
DISPLAY 0.723404 (-2100 1550);
PAINT GREEN (-2100 1550);
FORCEPROP 2 LAST $SEC 1
J 2
(-2200 1625);
DISPLAY 0.680851 (-2200 1625);
PAINT MONO (-2200 1625);
DISPLAY INVISIBLE (-2200 1625);
FORCEPROP 2 LAST CDS_SEC 1
J 2
(-2200 1625);
DISPLAY 0.680851 (-2200 1625);
DISPLAY INVISIBLE (-2200 1625);
FORCEPROP 2 LASTPIN (-2300 1550) $PN 1
J 0
(-2290 1560);
DISPLAY 0.808511 (-2290 1560);
FORCEPROP 2 LASTPIN (-2450 1550) $PN 2
J 2
(-2460 1560);
DISPLAY 0.808511 (-2460 1560);
FORCEPROP 2 LAST VALUE DIFF BUS_0.22UF
J 2
(-2525 1550);
DISPLAY 0.553191 (-2525 1550);
FORCEPROP 1 LAST CDS_LMAN_SYM_OUTLINE -25,50,25,-50
J 2
(-2375 1550);
DISPLAY 0.468085 (-2375 1550);
PAINT GREEN (-2375 1550);
DISPLAY INVISIBLE (-2375 1550);
FORCEPROP 2 LAST CDS_LIB pure_quanta
J 2
(-2375 1550);
DISPLAY INVISIBLE (-2375 1550);
FORCEPROP 1 LAST PIN_NAMES_ROTATE TRUE
J 2
(-2375 1550);
DISPLAY 0.489362 (-2375 1550);
PAINT GREEN (-2375 1550);
DISPLAY INVISIBLE (-2375 1550);
FORCEPROP 2 LAST VOLTAGE 6.3V
J 2
(-2725 1600);
DISPLAY 0.553191 (-2725 1600);
DISPLAY INVISIBLE (-2725 1600);
FORCEPROP 1 LAST MATERIAL X6S
J 2
(-2366 1629);
DISPLAY 0.574468 (-2366 1629);
PAINT GREEN (-2366 1629);
DISPLAY INVISIBLE (-2366 1629);
FORCEPROP 2 LAST PACK_TYPE C0201
J 2
(-2550 1600);
DISPLAY 0.553191 (-2550 1600);
DISPLAY INVISIBLE (-2550 1600);
FORCEPROP 2 LAST TOLERANCE 20%
J 2
(-2450 1600);
DISPLAY 0.553191 (-2450 1600);
DISPLAY INVISIBLE (-2450 1600);
FORCEPROP 1 LAST PATH I28
J 2
(-2375 1550);
DISPLAY 0.723404 (-2375 1550);
DISPLAY INVISIBLE (-2375 1550);
FORCEPROP 1 LAST PART_NUMBER SP_CH4221MEE01
J 2
(-2491 1638);
DISPLAY 0.574468 (-2491 1638);
PAINT GREEN (-2491 1638);
DISPLAY INVISIBLE (-2491 1638);
FORCEPROP 1 LAST LOCATION C6668
J 0
(-2125 1625);
DISPLAY 1.021277 (-2125 1625);
DISPLAY INVISIBLE (-2125 1625);
FORCEADD Q_CAP_DIFFBUS..2
R 2
(-2375 1750);
FORCEPROP 1 LAST LOCATION C6666
J 2
(-2100 1750);
DISPLAY 0.723404 (-2100 1750);
PAINT GREEN (-2100 1750);
FORCEPROP 2 LAST $SEC 1
J 2
(-2200 1825);
DISPLAY 0.680851 (-2200 1825);
PAINT MONO (-2200 1825);
DISPLAY INVISIBLE (-2200 1825);
FORCEPROP 2 LAST CDS_SEC 1
J 2
(-2200 1825);
DISPLAY 0.680851 (-2200 1825);
DISPLAY INVISIBLE (-2200 1825);
FORCEPROP 2 LASTPIN (-2300 1750) $PN 1
J 0
(-2290 1760);
DISPLAY 0.808511 (-2290 1760);
FORCEPROP 2 LASTPIN (-2450 1750) $PN 2
J 2
(-2460 1760);
DISPLAY 0.808511 (-2460 1760);
FORCEPROP 2 LAST VALUE DIFF BUS_0.22UF
J 2
(-2525 1750);
DISPLAY 0.553191 (-2525 1750);
FORCEPROP 1 LAST CDS_LMAN_SYM_OUTLINE -25,50,25,-50
J 2
(-2375 1750);
DISPLAY 0.468085 (-2375 1750);
PAINT GREEN (-2375 1750);
DISPLAY INVISIBLE (-2375 1750);
FORCEPROP 2 LAST CDS_LIB pure_quanta
J 2
(-2375 1750);
DISPLAY INVISIBLE (-2375 1750);
FORCEPROP 1 LAST PIN_NAMES_ROTATE TRUE
J 2
(-2375 1750);
DISPLAY 0.489362 (-2375 1750);
PAINT GREEN (-2375 1750);
DISPLAY INVISIBLE (-2375 1750);
FORCEPROP 2 LAST VOLTAGE 6.3V
J 2
(-2725 1800);
DISPLAY 0.553191 (-2725 1800);
DISPLAY INVISIBLE (-2725 1800);
FORCEPROP 1 LAST MATERIAL X6S
J 2
(-2366 1829);
DISPLAY 0.574468 (-2366 1829);
PAINT GREEN (-2366 1829);
DISPLAY INVISIBLE (-2366 1829);
FORCEPROP 2 LAST PACK_TYPE C0201
J 2
(-2550 1800);
DISPLAY 0.553191 (-2550 1800);
DISPLAY INVISIBLE (-2550 1800);
FORCEPROP 2 LAST TOLERANCE 20%
J 2
(-2450 1800);
DISPLAY 0.553191 (-2450 1800);
DISPLAY INVISIBLE (-2450 1800);
FORCEPROP 1 LAST PATH I29
J 2
(-2375 1750);
DISPLAY 0.723404 (-2375 1750);
DISPLAY INVISIBLE (-2375 1750);
FORCEPROP 1 LAST PART_NUMBER SP_CH4221MEE01
J 2
(-2491 1838);
DISPLAY 0.574468 (-2491 1838);
PAINT GREEN (-2491 1838);
DISPLAY INVISIBLE (-2491 1838);
FORCEPROP 1 LAST LOCATION C6666
J 0
(-2125 1825);
DISPLAY 1.021277 (-2125 1825);
DISPLAY INVISIBLE (-2125 1825);
FORCEADD TAP..1
R 2
(-3350 750);
FORCEPROP 3 LASTPIN (-3300 750) SIG_NAME P5E_CPU1_P1_TX_BUF_DN<7>
J 0
(-3290 760);
DISPLAY 0.659574 (-3290 760);
PAINT MONO (-3290 760);
DISPLAY INVISIBLE (-3290 760);
FORCEPROP 1 LASTPIN (-3300 750) BN 7
J 2
(-3288 758);
DISPLAY 0.680851 (-3288 758);
PAINT GREEN (-3288 758);
FORCEPROP 2 LAST CDS_LIB standard
J 0
(-3350 750);
DISPLAY INVISIBLE (-3350 750);
FORCEPROP 1 LAST BODY_TYPE PLUMBING
J 2
(-3350 800);
DISPLAY 0.872340 (-3350 800);
PAINT GREEN (-3350 800);
DISPLAY INVISIBLE (-3350 800);
FORCEPROP 1 LAST HDL_TAP TRUE
J 2
(-3675 625);
DISPLAY 0.872340 (-3675 625);
DISPLAY INVISIBLE (-3675 625);
FORCEPROP 1 LAST PATH I3
J 2
(-3348 750);
DISPLAY 0.872340 (-3348 750);
PAINT GREEN (-3348 750);
DISPLAY INVISIBLE (-3348 750);
FORCEADD Q_CAP_DIFFBUS..2
R 2
(-2375 1800);
FORCEPROP 1 LAST LOCATION C6665
J 2
(-2100 1800);
DISPLAY 0.723404 (-2100 1800);
PAINT GREEN (-2100 1800);
FORCEPROP 2 LAST $SEC 1
J 2
(-2200 1875);
DISPLAY 0.680851 (-2200 1875);
PAINT MONO (-2200 1875);
DISPLAY INVISIBLE (-2200 1875);
FORCEPROP 2 LAST CDS_SEC 1
J 2
(-2200 1875);
DISPLAY 0.680851 (-2200 1875);
DISPLAY INVISIBLE (-2200 1875);
FORCEPROP 2 LASTPIN (-2300 1800) $PN 1
J 0
(-2290 1810);
DISPLAY 0.808511 (-2290 1810);
FORCEPROP 2 LASTPIN (-2450 1800) $PN 2
J 2
(-2460 1810);
DISPLAY 0.808511 (-2460 1810);
FORCEPROP 2 LAST VALUE DIFF BUS_0.22UF
J 2
(-2525 1800);
DISPLAY 0.553191 (-2525 1800);
FORCEPROP 1 LAST CDS_LMAN_SYM_OUTLINE -25,50,25,-50
J 2
(-2375 1800);
DISPLAY 0.468085 (-2375 1800);
PAINT GREEN (-2375 1800);
DISPLAY INVISIBLE (-2375 1800);
FORCEPROP 2 LAST CDS_LIB pure_quanta
J 2
(-2375 1800);
DISPLAY INVISIBLE (-2375 1800);
FORCEPROP 1 LAST PIN_NAMES_ROTATE TRUE
J 2
(-2375 1800);
DISPLAY 0.489362 (-2375 1800);
PAINT GREEN (-2375 1800);
DISPLAY INVISIBLE (-2375 1800);
FORCEPROP 2 LAST VOLTAGE 6.3V
J 2
(-2725 1850);
DISPLAY 0.553191 (-2725 1850);
DISPLAY INVISIBLE (-2725 1850);
FORCEPROP 1 LAST MATERIAL X6S
J 2
(-2366 1879);
DISPLAY 0.574468 (-2366 1879);
PAINT GREEN (-2366 1879);
DISPLAY INVISIBLE (-2366 1879);
FORCEPROP 2 LAST PACK_TYPE C0201
J 2
(-2550 1850);
DISPLAY 0.553191 (-2550 1850);
DISPLAY INVISIBLE (-2550 1850);
FORCEPROP 2 LAST TOLERANCE 20%
J 2
(-2450 1850);
DISPLAY 0.553191 (-2450 1850);
DISPLAY INVISIBLE (-2450 1850);
FORCEPROP 1 LAST PATH I30
J 2
(-2375 1800);
DISPLAY 0.723404 (-2375 1800);
DISPLAY INVISIBLE (-2375 1800);
FORCEPROP 1 LAST PART_NUMBER SP_CH4221MEE01
J 2
(-2491 1888);
DISPLAY 0.574468 (-2491 1888);
PAINT GREEN (-2491 1888);
DISPLAY INVISIBLE (-2491 1888);
FORCEPROP 1 LAST LOCATION C6665
J 0
(-2125 1875);
DISPLAY 1.021277 (-2125 1875);
DISPLAY INVISIBLE (-2125 1875);
FORCEADD Q_CAP_DIFFBUS..2
R 2
(-2375 2000);
FORCEPROP 1 LAST LOCATION C6663
J 2
(-2075 2000);
DISPLAY 0.723404 (-2075 2000);
PAINT GREEN (-2075 2000);
FORCEPROP 2 LAST $SEC 1
J 2
(-2200 2075);
DISPLAY 0.680851 (-2200 2075);
PAINT MONO (-2200 2075);
DISPLAY INVISIBLE (-2200 2075);
FORCEPROP 2 LAST CDS_SEC 1
J 2
(-2200 2075);
DISPLAY 0.680851 (-2200 2075);
DISPLAY INVISIBLE (-2200 2075);
FORCEPROP 2 LASTPIN (-2300 2000) $PN 1
J 0
(-2290 2010);
DISPLAY 0.808511 (-2290 2010);
FORCEPROP 2 LASTPIN (-2450 2000) $PN 2
J 2
(-2460 2010);
DISPLAY 0.808511 (-2460 2010);
FORCEPROP 2 LAST VALUE DIFF BUS_0.22UF
J 2
(-2525 2000);
DISPLAY 0.553191 (-2525 2000);
FORCEPROP 1 LAST CDS_LMAN_SYM_OUTLINE -25,50,25,-50
J 2
(-2375 2000);
DISPLAY 0.468085 (-2375 2000);
PAINT GREEN (-2375 2000);
DISPLAY INVISIBLE (-2375 2000);
FORCEPROP 2 LAST CDS_LIB pure_quanta
J 2
(-2375 2000);
DISPLAY INVISIBLE (-2375 2000);
FORCEPROP 1 LAST PIN_NAMES_ROTATE TRUE
J 2
(-2375 2000);
DISPLAY 0.489362 (-2375 2000);
PAINT GREEN (-2375 2000);
DISPLAY INVISIBLE (-2375 2000);
FORCEPROP 2 LAST VOLTAGE 6.3V
J 2
(-2725 2050);
DISPLAY 0.553191 (-2725 2050);
DISPLAY INVISIBLE (-2725 2050);
FORCEPROP 1 LAST MATERIAL X6S
J 2
(-2366 2079);
DISPLAY 0.574468 (-2366 2079);
PAINT GREEN (-2366 2079);
DISPLAY INVISIBLE (-2366 2079);
FORCEPROP 2 LAST PACK_TYPE C0201
J 2
(-2550 2050);
DISPLAY 0.553191 (-2550 2050);
DISPLAY INVISIBLE (-2550 2050);
FORCEPROP 2 LAST TOLERANCE 20%
J 2
(-2450 2050);
DISPLAY 0.553191 (-2450 2050);
DISPLAY INVISIBLE (-2450 2050);
FORCEPROP 1 LAST PATH I31
J 2
(-2375 2000);
DISPLAY 0.723404 (-2375 2000);
DISPLAY INVISIBLE (-2375 2000);
FORCEPROP 1 LAST PART_NUMBER SP_CH4221MEE01
J 2
(-2491 2088);
DISPLAY 0.574468 (-2491 2088);
PAINT GREEN (-2491 2088);
DISPLAY INVISIBLE (-2491 2088);
FORCEPROP 1 LAST LOCATION C6663
J 0
(-2125 2075);
DISPLAY 1.021277 (-2125 2075);
DISPLAY INVISIBLE (-2125 2075);
FORCEADD Q_CAP_DIFFBUS..2
R 2
(-2375 1950);
FORCEPROP 1 LAST LOCATION C6664
J 2
(-2075 1950);
DISPLAY 0.723404 (-2075 1950);
PAINT GREEN (-2075 1950);
FORCEPROP 2 LAST $SEC 1
J 2
(-2200 2025);
DISPLAY 0.680851 (-2200 2025);
PAINT MONO (-2200 2025);
DISPLAY INVISIBLE (-2200 2025);
FORCEPROP 2 LAST CDS_SEC 1
J 2
(-2200 2025);
DISPLAY 0.680851 (-2200 2025);
DISPLAY INVISIBLE (-2200 2025);
FORCEPROP 2 LASTPIN (-2300 1950) $PN 1
J 0
(-2290 1960);
DISPLAY 0.808511 (-2290 1960);
FORCEPROP 2 LASTPIN (-2450 1950) $PN 2
J 2
(-2460 1960);
DISPLAY 0.808511 (-2460 1960);
FORCEPROP 2 LAST VALUE DIFF BUS_0.22UF
J 2
(-2525 1950);
DISPLAY 0.553191 (-2525 1950);
FORCEPROP 1 LAST CDS_LMAN_SYM_OUTLINE -25,50,25,-50
J 2
(-2375 1950);
DISPLAY 0.468085 (-2375 1950);
PAINT GREEN (-2375 1950);
DISPLAY INVISIBLE (-2375 1950);
FORCEPROP 2 LAST CDS_LIB pure_quanta
J 2
(-2375 1950);
DISPLAY INVISIBLE (-2375 1950);
FORCEPROP 1 LAST PIN_NAMES_ROTATE TRUE
J 2
(-2375 1950);
DISPLAY 0.489362 (-2375 1950);
PAINT GREEN (-2375 1950);
DISPLAY INVISIBLE (-2375 1950);
FORCEPROP 2 LAST VOLTAGE 6.3V
J 2
(-2725 2000);
DISPLAY 0.553191 (-2725 2000);
DISPLAY INVISIBLE (-2725 2000);
FORCEPROP 1 LAST MATERIAL X6S
J 2
(-2366 2029);
DISPLAY 0.574468 (-2366 2029);
PAINT GREEN (-2366 2029);
DISPLAY INVISIBLE (-2366 2029);
FORCEPROP 2 LAST PACK_TYPE C0201
J 2
(-2550 2000);
DISPLAY 0.553191 (-2550 2000);
DISPLAY INVISIBLE (-2550 2000);
FORCEPROP 2 LAST TOLERANCE 20%
J 2
(-2450 2000);
DISPLAY 0.553191 (-2450 2000);
DISPLAY INVISIBLE (-2450 2000);
FORCEPROP 1 LAST PATH I32
J 2
(-2375 1950);
DISPLAY 0.723404 (-2375 1950);
DISPLAY INVISIBLE (-2375 1950);
FORCEPROP 1 LAST PART_NUMBER SP_CH4221MEE01
J 2
(-2491 2038);
DISPLAY 0.574468 (-2491 2038);
PAINT GREEN (-2491 2038);
DISPLAY INVISIBLE (-2491 2038);
FORCEPROP 1 LAST LOCATION C6664
J 0
(-2125 2025);
DISPLAY 1.021277 (-2125 2025);
DISPLAY INVISIBLE (-2125 2025);
FORCEADD Q_CAP_DIFFBUS..2
R 2
(-2375 2150);
FORCEPROP 1 LAST LOCATION C6662
J 2
(-2075 2150);
DISPLAY 0.723404 (-2075 2150);
PAINT GREEN (-2075 2150);
FORCEPROP 2 LAST $SEC 1
J 2
(-2200 2225);
DISPLAY 0.680851 (-2200 2225);
PAINT MONO (-2200 2225);
DISPLAY INVISIBLE (-2200 2225);
FORCEPROP 2 LAST CDS_SEC 1
J 2
(-2200 2225);
DISPLAY 0.680851 (-2200 2225);
DISPLAY INVISIBLE (-2200 2225);
FORCEPROP 2 LASTPIN (-2300 2150) $PN 1
J 0
(-2290 2160);
DISPLAY 0.808511 (-2290 2160);
FORCEPROP 2 LASTPIN (-2450 2150) $PN 2
J 2
(-2460 2160);
DISPLAY 0.808511 (-2460 2160);
FORCEPROP 2 LAST VALUE DIFF BUS_0.22UF
J 2
(-2525 2150);
DISPLAY 0.553191 (-2525 2150);
FORCEPROP 1 LAST CDS_LMAN_SYM_OUTLINE -25,50,25,-50
J 2
(-2375 2150);
DISPLAY 0.468085 (-2375 2150);
PAINT GREEN (-2375 2150);
DISPLAY INVISIBLE (-2375 2150);
FORCEPROP 2 LAST CDS_LIB pure_quanta
J 2
(-2375 2150);
DISPLAY INVISIBLE (-2375 2150);
FORCEPROP 1 LAST PIN_NAMES_ROTATE TRUE
J 2
(-2375 2150);
DISPLAY 0.489362 (-2375 2150);
PAINT GREEN (-2375 2150);
DISPLAY INVISIBLE (-2375 2150);
FORCEPROP 2 LAST VOLTAGE 6.3V
J 2
(-2725 2200);
DISPLAY 0.553191 (-2725 2200);
DISPLAY INVISIBLE (-2725 2200);
FORCEPROP 1 LAST MATERIAL X6S
J 2
(-2366 2229);
DISPLAY 0.574468 (-2366 2229);
PAINT GREEN (-2366 2229);
DISPLAY INVISIBLE (-2366 2229);
FORCEPROP 2 LAST PACK_TYPE C0201
J 2
(-2550 2200);
DISPLAY 0.553191 (-2550 2200);
DISPLAY INVISIBLE (-2550 2200);
FORCEPROP 2 LAST TOLERANCE 20%
J 2
(-2450 2200);
DISPLAY 0.553191 (-2450 2200);
DISPLAY INVISIBLE (-2450 2200);
FORCEPROP 1 LAST PATH I33
J 2
(-2375 2150);
DISPLAY 0.723404 (-2375 2150);
DISPLAY INVISIBLE (-2375 2150);
FORCEPROP 1 LAST PART_NUMBER SP_CH4221MEE01
J 2
(-2491 2238);
DISPLAY 0.574468 (-2491 2238);
PAINT GREEN (-2491 2238);
DISPLAY INVISIBLE (-2491 2238);
FORCEPROP 1 LAST LOCATION C6662
J 0
(-2125 2225);
DISPLAY 1.021277 (-2125 2225);
DISPLAY INVISIBLE (-2125 2225);
FORCEADD TAP..1
(-1825 1200);
FORCEPROP 3 LASTPIN (-1875 1200) SIG_NAME P5E_CPU1_P1_TX_BUF_C_DP<5>
J 0
(-1865 1210);
DISPLAY 0.659574 (-1865 1210);
PAINT MONO (-1865 1210);
DISPLAY INVISIBLE (-1865 1210);
FORCEPROP 1 LASTPIN (-1875 1200) BN 5
J 0
(-1887 1208);
DISPLAY 0.680851 (-1887 1208);
PAINT GREEN (-1887 1208);
FORCEPROP 2 LAST CDS_LIB standard
J 0
(-1825 1200);
DISPLAY INVISIBLE (-1825 1200);
FORCEPROP 1 LAST BODY_TYPE PLUMBING
J 0
(-1825 1250);
DISPLAY 0.872340 (-1825 1250);
PAINT GREEN (-1825 1250);
DISPLAY INVISIBLE (-1825 1250);
FORCEPROP 1 LAST HDL_TAP TRUE
J 0
(-1500 1075);
DISPLAY 0.872340 (-1500 1075);
DISPLAY INVISIBLE (-1500 1075);
FORCEPROP 1 LAST PATH I34
J 0
(-1827 1200);
DISPLAY 0.872340 (-1827 1200);
PAINT GREEN (-1827 1200);
DISPLAY INVISIBLE (-1827 1200);
FORCEADD TAP..1
(-1825 1600);
FORCEPROP 3 LASTPIN (-1875 1600) SIG_NAME P5E_CPU1_P1_TX_BUF_C_DP<3>
J 0
(-1865 1610);
DISPLAY 0.659574 (-1865 1610);
PAINT MONO (-1865 1610);
DISPLAY INVISIBLE (-1865 1610);
FORCEPROP 1 LASTPIN (-1875 1600) BN 3
J 0
(-1887 1608);
DISPLAY 0.680851 (-1887 1608);
PAINT GREEN (-1887 1608);
FORCEPROP 2 LAST CDS_LIB standard
J 0
(-1825 1600);
DISPLAY INVISIBLE (-1825 1600);
FORCEPROP 1 LAST BODY_TYPE PLUMBING
J 0
(-1825 1650);
DISPLAY 0.872340 (-1825 1650);
PAINT GREEN (-1825 1650);
DISPLAY INVISIBLE (-1825 1650);
FORCEPROP 1 LAST HDL_TAP TRUE
J 0
(-1500 1475);
DISPLAY 0.872340 (-1500 1475);
DISPLAY INVISIBLE (-1500 1475);
FORCEPROP 1 LAST PATH I35
J 0
(-1827 1600);
DISPLAY 0.872340 (-1827 1600);
PAINT GREEN (-1827 1600);
DISPLAY INVISIBLE (-1827 1600);
FORCEADD TAP..1
(-1825 1400);
FORCEPROP 3 LASTPIN (-1875 1400) SIG_NAME P5E_CPU1_P1_TX_BUF_C_DP<4>
J 0
(-1865 1410);
DISPLAY 0.659574 (-1865 1410);
PAINT MONO (-1865 1410);
DISPLAY INVISIBLE (-1865 1410);
FORCEPROP 1 LASTPIN (-1875 1400) BN 4
J 0
(-1887 1408);
DISPLAY 0.680851 (-1887 1408);
PAINT GREEN (-1887 1408);
FORCEPROP 2 LAST CDS_LIB standard
J 0
(-1825 1400);
DISPLAY INVISIBLE (-1825 1400);
FORCEPROP 1 LAST BODY_TYPE PLUMBING
J 0
(-1825 1450);
DISPLAY 0.872340 (-1825 1450);
PAINT GREEN (-1825 1450);
DISPLAY INVISIBLE (-1825 1450);
FORCEPROP 1 LAST HDL_TAP TRUE
J 0
(-1500 1275);
DISPLAY 0.872340 (-1500 1275);
DISPLAY INVISIBLE (-1500 1275);
FORCEPROP 1 LAST PATH I36
J 0
(-1827 1400);
DISPLAY 0.872340 (-1827 1400);
PAINT GREEN (-1827 1400);
DISPLAY INVISIBLE (-1827 1400);
FORCEADD TAP..1
(-1825 1800);
FORCEPROP 3 LASTPIN (-1875 1800) SIG_NAME P5E_CPU1_P1_TX_BUF_C_DP<2>
J 0
(-1865 1810);
DISPLAY 0.659574 (-1865 1810);
PAINT MONO (-1865 1810);
DISPLAY INVISIBLE (-1865 1810);
FORCEPROP 1 LASTPIN (-1875 1800) BN 2
J 0
(-1887 1808);
DISPLAY 0.680851 (-1887 1808);
PAINT GREEN (-1887 1808);
FORCEPROP 2 LAST CDS_LIB standard
J 0
(-1825 1800);
DISPLAY INVISIBLE (-1825 1800);
FORCEPROP 1 LAST BODY_TYPE PLUMBING
J 0
(-1825 1850);
DISPLAY 0.872340 (-1825 1850);
PAINT GREEN (-1825 1850);
DISPLAY INVISIBLE (-1825 1850);
FORCEPROP 1 LAST HDL_TAP TRUE
J 0
(-1500 1675);
DISPLAY 0.872340 (-1500 1675);
DISPLAY INVISIBLE (-1500 1675);
FORCEPROP 1 LAST PATH I37
J 0
(-1827 1800);
DISPLAY 0.872340 (-1827 1800);
PAINT GREEN (-1827 1800);
DISPLAY INVISIBLE (-1827 1800);
FORCEADD TAP..1
(-1825 2000);
FORCEPROP 3 LASTPIN (-1875 2000) SIG_NAME P5E_CPU1_P1_TX_BUF_C_DP<1>
J 0
(-1865 2010);
DISPLAY 0.659574 (-1865 2010);
PAINT MONO (-1865 2010);
DISPLAY INVISIBLE (-1865 2010);
FORCEPROP 1 LASTPIN (-1875 2000) BN 1
J 0
(-1887 2008);
DISPLAY 0.680851 (-1887 2008);
PAINT GREEN (-1887 2008);
FORCEPROP 2 LAST CDS_LIB standard
J 0
(-1825 2000);
DISPLAY INVISIBLE (-1825 2000);
FORCEPROP 1 LAST BODY_TYPE PLUMBING
J 0
(-1825 2050);
DISPLAY 0.872340 (-1825 2050);
PAINT GREEN (-1825 2050);
DISPLAY INVISIBLE (-1825 2050);
FORCEPROP 1 LAST HDL_TAP TRUE
J 0
(-1500 1875);
DISPLAY 0.872340 (-1500 1875);
DISPLAY INVISIBLE (-1500 1875);
FORCEPROP 1 LAST PATH I38
J 0
(-1827 2000);
DISPLAY 0.872340 (-1827 2000);
PAINT GREEN (-1827 2000);
DISPLAY INVISIBLE (-1827 2000);
FORCEADD TAP..1
R 2
(-3350 2150);
FORCEPROP 3 LASTPIN (-3300 2150) SIG_NAME P5E_CPU1_P1_TX_BUF_DN<0>
J 0
(-3290 2160);
DISPLAY 0.659574 (-3290 2160);
PAINT MONO (-3290 2160);
DISPLAY INVISIBLE (-3290 2160);
FORCEPROP 1 LASTPIN (-3300 2150) BN 0
J 2
(-3288 2158);
DISPLAY 0.680851 (-3288 2158);
PAINT GREEN (-3288 2158);
FORCEPROP 2 LAST CDS_LIB standard
J 0
(-3350 2150);
DISPLAY INVISIBLE (-3350 2150);
FORCEPROP 1 LAST BODY_TYPE PLUMBING
J 2
(-3350 2200);
DISPLAY 0.872340 (-3350 2200);
PAINT GREEN (-3350 2200);
DISPLAY INVISIBLE (-3350 2200);
FORCEPROP 1 LAST HDL_TAP TRUE
J 2
(-3675 2025);
DISPLAY 0.872340 (-3675 2025);
DISPLAY INVISIBLE (-3675 2025);
FORCEPROP 1 LAST PATH I39
J 2
(-3348 2150);
DISPLAY 0.872340 (-3348 2150);
PAINT GREEN (-3348 2150);
DISPLAY INVISIBLE (-3348 2150);
FORCEADD TAP..1
R 2
(-3350 950);
FORCEPROP 3 LASTPIN (-3300 950) SIG_NAME P5E_CPU1_P1_TX_BUF_DN<6>
J 0
(-3290 960);
DISPLAY 0.659574 (-3290 960);
PAINT MONO (-3290 960);
DISPLAY INVISIBLE (-3290 960);
FORCEPROP 1 LASTPIN (-3300 950) BN 6
J 2
(-3288 958);
DISPLAY 0.680851 (-3288 958);
PAINT GREEN (-3288 958);
FORCEPROP 2 LAST CDS_LIB standard
J 0
(-3350 950);
DISPLAY INVISIBLE (-3350 950);
FORCEPROP 1 LAST BODY_TYPE PLUMBING
J 2
(-3350 1000);
DISPLAY 0.872340 (-3350 1000);
PAINT GREEN (-3350 1000);
DISPLAY INVISIBLE (-3350 1000);
FORCEPROP 1 LAST HDL_TAP TRUE
J 2
(-3675 825);
DISPLAY 0.872340 (-3675 825);
DISPLAY INVISIBLE (-3675 825);
FORCEPROP 1 LAST PATH I4
J 2
(-3348 950);
DISPLAY 0.872340 (-3348 950);
PAINT GREEN (-3348 950);
DISPLAY INVISIBLE (-3348 950);
FORCEADD TAP..1
R 2
(-3100 2200);
FORCEPROP 3 LASTPIN (-3050 2200) SIG_NAME P5E_CPU1_P1_TX_BUF_DP<0>
J 0
(-3040 2210);
DISPLAY 0.659574 (-3040 2210);
PAINT MONO (-3040 2210);
DISPLAY INVISIBLE (-3040 2210);
FORCEPROP 1 LASTPIN (-3050 2200) BN 0
J 2
(-3038 2208);
DISPLAY 0.680851 (-3038 2208);
PAINT GREEN (-3038 2208);
FORCEPROP 2 LAST CDS_LIB standard
J 0
(-3100 2200);
DISPLAY INVISIBLE (-3100 2200);
FORCEPROP 1 LAST BODY_TYPE PLUMBING
J 2
(-3100 2250);
DISPLAY 0.872340 (-3100 2250);
PAINT GREEN (-3100 2250);
DISPLAY INVISIBLE (-3100 2250);
FORCEPROP 1 LAST HDL_TAP TRUE
J 2
(-3425 2075);
DISPLAY 0.872340 (-3425 2075);
DISPLAY INVISIBLE (-3425 2075);
FORCEPROP 1 LAST PATH I40
J 2
(-3098 2200);
DISPLAY 0.872340 (-3098 2200);
PAINT GREEN (-3098 2200);
DISPLAY INVISIBLE (-3098 2200);
FORCEADD PT5161LRS..10
(-7525 4575);
FORCEPROP 1 LAST LOCATION U6015
J 0
(-7875 6200);
DISPLAY 0.723404 (-7875 6200);
PAINT GREEN (-7875 6200);
FORCEPROP 0 LAST $SEC 10
J 0
(-7875 6350);
DISPLAY 0.680851 (-7875 6350);
PAINT MONO (-7875 6350);
DISPLAY INVISIBLE (-7875 6350);
FORCEPROP 0 LAST CDS_SEC 10
J 0
(-7875 6350);
DISPLAY 0.680851 (-7875 6350);
DISPLAY INVISIBLE (-7875 6350);
FORCEPROP 0 LASTPIN (-7075 5725) $PN P10
J 0
(-7065 5735);
DISPLAY 0.680851 (-7065 5735);
PAINT MONO (-7065 5735);
FORCEPROP 0 LASTPIN (-7075 5375) $PN AA10
J 0
(-7065 5385);
DISPLAY 0.680851 (-7065 5385);
PAINT MONO (-7065 5385);
FORCEPROP 0 LASTPIN (-7075 5025) $PN AH10
J 0
(-7065 5035);
DISPLAY 0.680851 (-7065 5035);
PAINT MONO (-7065 5035);
FORCEPROP 0 LASTPIN (-7075 4675) $PN AR10
J 0
(-7065 4685);
DISPLAY 0.680851 (-7065 4685);
PAINT MONO (-7065 4685);
FORCEPROP 0 LASTPIN (-7075 4325) $PN BB10
J 0
(-7065 4335);
DISPLAY 0.680851 (-7065 4335);
PAINT MONO (-7065 4335);
FORCEPROP 0 LASTPIN (-7075 3975) $PN BJ10
J 0
(-7065 3985);
DISPLAY 0.680851 (-7065 3985);
PAINT MONO (-7065 3985);
FORCEPROP 0 LASTPIN (-7075 3625) $PN BT10
J 0
(-7065 3635);
DISPLAY 0.680851 (-7065 3635);
PAINT MONO (-7065 3635);
FORCEPROP 0 LASTPIN (-7075 3275) $PN CC10
J 0
(-7065 3285);
DISPLAY 0.680851 (-7065 3285);
PAINT MONO (-7065 3285);
FORCEPROP 0 LASTPIN (-7075 5825) $PN M7
J 0
(-7065 5835);
DISPLAY 0.680851 (-7065 5835);
PAINT MONO (-7065 5835);
FORCEPROP 0 LASTPIN (-7075 5475) $PN W7
J 0
(-7065 5485);
DISPLAY 0.680851 (-7065 5485);
PAINT MONO (-7065 5485);
FORCEPROP 0 LASTPIN (-7075 5125) $PN AF7
J 0
(-7065 5135);
DISPLAY 0.680851 (-7065 5135);
PAINT MONO (-7065 5135);
FORCEPROP 0 LASTPIN (-7075 4775) $PN AN7
J 0
(-7065 4785);
DISPLAY 0.680851 (-7065 4785);
PAINT MONO (-7065 4785);
FORCEPROP 0 LASTPIN (-7075 4425) $PN AY7
J 0
(-7065 4435);
DISPLAY 0.680851 (-7065 4435);
PAINT MONO (-7065 4435);
FORCEPROP 0 LASTPIN (-7075 4075) $PN BG7
J 0
(-7065 4085);
DISPLAY 0.680851 (-7065 4085);
PAINT MONO (-7065 4085);
FORCEPROP 0 LASTPIN (-7075 3725) $PN BP7
J 0
(-7065 3735);
DISPLAY 0.680851 (-7065 3735);
PAINT MONO (-7065 3735);
FORCEPROP 0 LASTPIN (-7075 3375) $PN CA7
J 0
(-7065 3385);
DISPLAY 0.680851 (-7065 3385);
PAINT MONO (-7065 3385);
FORCEPROP 1 LAST MATERIAL IC
J 0
(-7875 6050);
DISPLAY 0.723404 (-7875 6050);
PAINT GREEN (-7875 6050);
FORCEPROP 2 LAST VALUE PT5161LRS
J 0
(-7875 6250);
DISPLAY 0.680851 (-7875 6250);
FORCEPROP 2 LAST PART_TYPE SMLF
J 0
(-7875 6300);
DISPLAY 0.680851 (-7875 6300);
FORCEPROP 1 LAST NEEDS_NO_SIZE TRUE
J 0
(-7525 4575);
DISPLAY 0.723404 (-7525 4575);
PAINT GREEN (-7525 4575);
DISPLAY INVISIBLE (-7525 4575);
FORCEPROP 1 LAST CDS_LMAN_SYM_OUTLINE -350,1450,300,-1400
J 0
(-7525 4575);
DISPLAY 0.468085 (-7525 4575);
PAINT GREEN (-7525 4575);
DISPLAY INVISIBLE (-7525 4575);
FORCEPROP 2 LAST CDS_LIB pure_quanta
J 0
(-7525 4575);
DISPLAY INVISIBLE (-7525 4575);
FORCEPROP 1 LAST PATH I41
J 0
(-7525 4575);
DISPLAY 0.723404 (-7525 4575);
PAINT GREEN (-7525 4575);
DISPLAY INVISIBLE (-7525 4575);
FORCEPROP 1 LAST PART_NUMBER AJ051610U03
J 0
(-7875 6125);
DISPLAY 0.723404 (-7875 6125);
PAINT GREEN (-7875 6125);
DISPLAY INVISIBLE (-7875 6125);
FORCEADD Q_CAP_DIFFBUS..2
R 2
(-2375 2200);
FORCEPROP 1 LAST LOCATION C6661
J 2
(-2075 2200);
DISPLAY 0.723404 (-2075 2200);
PAINT GREEN (-2075 2200);
FORCEPROP 2 LAST $SEC 1
J 2
(-2200 2275);
DISPLAY 0.680851 (-2200 2275);
PAINT MONO (-2200 2275);
DISPLAY INVISIBLE (-2200 2275);
FORCEPROP 2 LAST CDS_SEC 1
J 2
(-2200 2275);
DISPLAY 0.680851 (-2200 2275);
DISPLAY INVISIBLE (-2200 2275);
FORCEPROP 2 LASTPIN (-2300 2200) $PN 1
J 0
(-2290 2210);
DISPLAY 0.808511 (-2290 2210);
FORCEPROP 2 LASTPIN (-2450 2200) $PN 2
J 2
(-2460 2210);
DISPLAY 0.808511 (-2460 2210);
FORCEPROP 2 LAST PACK_TYPE C0201
J 2
(-2425 2350);
DISPLAY 0.553191 (-2425 2350);
PAINT GREEN (-2425 2350);
FORCEPROP 2 LAST TOLERANCE 20%
J 2
(-2325 2350);
DISPLAY 0.553191 (-2325 2350);
PAINT GREEN (-2325 2350);
FORCEPROP 1 LAST MATERIAL X6S
J 2
(-2466 2404);
DISPLAY 0.574468 (-2466 2404);
PAINT GREEN (-2466 2404);
FORCEPROP 2 LAST VOLTAGE 6.3V
J 2
(-2200 2350);
DISPLAY 0.553191 (-2200 2350);
PAINT GREEN (-2200 2350);
FORCEPROP 2 LAST VALUE DIFF BUS_0.22UF
J 2
(-2525 2200);
DISPLAY 0.553191 (-2525 2200);
FORCEPROP 2 LAST CDS_LIB pure_quanta
J 2
(-2375 2200);
DISPLAY INVISIBLE (-2375 2200);
FORCEPROP 1 LAST CDS_LMAN_SYM_OUTLINE -25,50,25,-50
J 2
(-2375 2200);
DISPLAY 0.468085 (-2375 2200);
PAINT GREEN (-2375 2200);
DISPLAY INVISIBLE (-2375 2200);
FORCEPROP 1 LAST PIN_NAMES_ROTATE TRUE
J 2
(-2375 2200);
DISPLAY 0.489362 (-2375 2200);
PAINT GREEN (-2375 2200);
DISPLAY INVISIBLE (-2375 2200);
FORCEPROP 1 LAST PATH I42
J 2
(-2375 2200);
DISPLAY 0.723404 (-2375 2200);
DISPLAY INVISIBLE (-2375 2200);
FORCEPROP 1 LAST PART_NUMBER SP_CH4221MEE01
J 2
(-2191 2288);
DISPLAY 0.574468 (-2191 2288);
PAINT GREEN (-2191 2288);
DISPLAY INVISIBLE (-2191 2288);
FORCEPROP 1 LAST LOCATION C6661
J 0
(-2125 2275);
DISPLAY 1.021277 (-2125 2275);
DISPLAY INVISIBLE (-2125 2275);
FORCEADD TAP..1
(-1825 2200);
FORCEPROP 3 LASTPIN (-1875 2200) SIG_NAME P5E_CPU1_P1_TX_BUF_C_DP<0>
J 0
(-1865 2210);
DISPLAY 0.659574 (-1865 2210);
PAINT MONO (-1865 2210);
DISPLAY INVISIBLE (-1865 2210);
FORCEPROP 1 LASTPIN (-1875 2200) BN 0
J 0
(-1887 2208);
DISPLAY 0.680851 (-1887 2208);
PAINT GREEN (-1887 2208);
FORCEPROP 2 LAST CDS_LIB standard
J 0
(-1825 2200);
DISPLAY INVISIBLE (-1825 2200);
FORCEPROP 1 LAST BODY_TYPE PLUMBING
J 0
(-1825 2250);
DISPLAY 0.872340 (-1825 2250);
PAINT GREEN (-1825 2250);
DISPLAY INVISIBLE (-1825 2250);
FORCEPROP 1 LAST HDL_TAP TRUE
J 0
(-1500 2075);
DISPLAY 0.872340 (-1500 2075);
DISPLAY INVISIBLE (-1500 2075);
FORCEPROP 1 LAST PATH I43
J 0
(-1827 2200);
DISPLAY 0.872340 (-1827 2200);
PAINT GREEN (-1827 2200);
DISPLAY INVISIBLE (-1827 2200);
FORCEADD TAP..1
(-6800 3375);
FORCEPROP 3 LASTPIN (-6850 3375) SIG_NAME P5E_CPU1_P1_TX_BUF_DP<8>
J 0
(-6840 3385);
DISPLAY 0.659574 (-6840 3385);
PAINT MONO (-6840 3385);
DISPLAY INVISIBLE (-6840 3385);
FORCEPROP 1 LASTPIN (-6850 3375) BN 8
J 0
(-6862 3383);
DISPLAY 0.680851 (-6862 3383);
PAINT GREEN (-6862 3383);
FORCEPROP 2 LAST CDS_LIB standard
J 0
(-6800 3375);
DISPLAY INVISIBLE (-6800 3375);
FORCEPROP 1 LAST BODY_TYPE PLUMBING
J 0
(-6800 3425);
DISPLAY 0.872340 (-6800 3425);
PAINT GREEN (-6800 3425);
DISPLAY INVISIBLE (-6800 3425);
FORCEPROP 1 LAST HDL_TAP TRUE
J 0
(-6475 3250);
DISPLAY 0.872340 (-6475 3250);
DISPLAY INVISIBLE (-6475 3250);
FORCEPROP 1 LAST PATH I44
J 0
(-6802 3375);
DISPLAY 0.872340 (-6802 3375);
PAINT GREEN (-6802 3375);
DISPLAY INVISIBLE (-6802 3375);
FORCEADD TAP..1
(-6600 3275);
FORCEPROP 3 LASTPIN (-6650 3275) SIG_NAME P5E_CPU1_P1_TX_BUF_DN<8>
J 0
(-6640 3285);
DISPLAY 0.659574 (-6640 3285);
PAINT MONO (-6640 3285);
DISPLAY INVISIBLE (-6640 3285);
FORCEPROP 1 LASTPIN (-6650 3275) BN 8
J 0
(-6662 3283);
DISPLAY 0.680851 (-6662 3283);
PAINT GREEN (-6662 3283);
FORCEPROP 2 LAST CDS_LIB standard
J 0
(-6600 3275);
DISPLAY INVISIBLE (-6600 3275);
FORCEPROP 1 LAST BODY_TYPE PLUMBING
J 0
(-6600 3325);
DISPLAY 0.872340 (-6600 3325);
PAINT GREEN (-6600 3325);
DISPLAY INVISIBLE (-6600 3325);
FORCEPROP 1 LAST HDL_TAP TRUE
J 0
(-6275 3150);
DISPLAY 0.872340 (-6275 3150);
DISPLAY INVISIBLE (-6275 3150);
FORCEPROP 1 LAST PATH I45
J 0
(-6602 3275);
DISPLAY 0.872340 (-6602 3275);
PAINT GREEN (-6602 3275);
DISPLAY INVISIBLE (-6602 3275);
FORCEADD TAP..1
(-6600 3625);
FORCEPROP 3 LASTPIN (-6650 3625) SIG_NAME P5E_CPU1_P1_TX_BUF_DN<9>
J 0
(-6640 3635);
DISPLAY 0.659574 (-6640 3635);
PAINT MONO (-6640 3635);
DISPLAY INVISIBLE (-6640 3635);
FORCEPROP 1 LASTPIN (-6650 3625) BN 9
J 0
(-6662 3633);
DISPLAY 0.680851 (-6662 3633);
PAINT GREEN (-6662 3633);
FORCEPROP 2 LAST CDS_LIB standard
J 0
(-6600 3625);
DISPLAY INVISIBLE (-6600 3625);
FORCEPROP 1 LAST BODY_TYPE PLUMBING
J 0
(-6600 3675);
DISPLAY 0.872340 (-6600 3675);
PAINT GREEN (-6600 3675);
DISPLAY INVISIBLE (-6600 3675);
FORCEPROP 1 LAST HDL_TAP TRUE
J 0
(-6275 3500);
DISPLAY 0.872340 (-6275 3500);
DISPLAY INVISIBLE (-6275 3500);
FORCEPROP 1 LAST PATH I46
J 0
(-6602 3625);
DISPLAY 0.872340 (-6602 3625);
PAINT GREEN (-6602 3625);
DISPLAY INVISIBLE (-6602 3625);
FORCEADD TAP..1
(-6800 3725);
FORCEPROP 3 LASTPIN (-6850 3725) SIG_NAME P5E_CPU1_P1_TX_BUF_DP<9>
J 0
(-6840 3735);
DISPLAY 0.659574 (-6840 3735);
PAINT MONO (-6840 3735);
DISPLAY INVISIBLE (-6840 3735);
FORCEPROP 1 LASTPIN (-6850 3725) BN 9
J 0
(-6862 3733);
DISPLAY 0.680851 (-6862 3733);
PAINT GREEN (-6862 3733);
FORCEPROP 2 LAST CDS_LIB standard
J 0
(-6800 3725);
DISPLAY INVISIBLE (-6800 3725);
FORCEPROP 1 LAST BODY_TYPE PLUMBING
J 0
(-6800 3775);
DISPLAY 0.872340 (-6800 3775);
PAINT GREEN (-6800 3775);
DISPLAY INVISIBLE (-6800 3775);
FORCEPROP 1 LAST HDL_TAP TRUE
J 0
(-6475 3600);
DISPLAY 0.872340 (-6475 3600);
DISPLAY INVISIBLE (-6475 3600);
FORCEPROP 1 LAST PATH I47
J 0
(-6802 3725);
DISPLAY 0.872340 (-6802 3725);
PAINT GREEN (-6802 3725);
DISPLAY INVISIBLE (-6802 3725);
FORCEADD TAP..1
(-6800 4075);
FORCEPROP 3 LASTPIN (-6850 4075) SIG_NAME P5E_CPU1_P1_TX_BUF_DP<10>
J 0
(-6840 4085);
DISPLAY 0.659574 (-6840 4085);
PAINT MONO (-6840 4085);
DISPLAY INVISIBLE (-6840 4085);
FORCEPROP 1 LASTPIN (-6850 4075) BN 10
J 0
(-6862 4083);
DISPLAY 0.680851 (-6862 4083);
PAINT GREEN (-6862 4083);
FORCEPROP 2 LAST CDS_LIB standard
J 0
(-6800 4075);
DISPLAY INVISIBLE (-6800 4075);
FORCEPROP 1 LAST BODY_TYPE PLUMBING
J 0
(-6800 4125);
DISPLAY 0.872340 (-6800 4125);
PAINT GREEN (-6800 4125);
DISPLAY INVISIBLE (-6800 4125);
FORCEPROP 1 LAST HDL_TAP TRUE
J 0
(-6475 3950);
DISPLAY 0.872340 (-6475 3950);
DISPLAY INVISIBLE (-6475 3950);
FORCEPROP 1 LAST PATH I48
J 0
(-6802 4075);
DISPLAY 0.872340 (-6802 4075);
PAINT GREEN (-6802 4075);
DISPLAY INVISIBLE (-6802 4075);
FORCEADD TAP..1
(-6600 3975);
FORCEPROP 3 LASTPIN (-6650 3975) SIG_NAME P5E_CPU1_P1_TX_BUF_DN<10>
J 0
(-6640 3985);
DISPLAY 0.659574 (-6640 3985);
PAINT MONO (-6640 3985);
DISPLAY INVISIBLE (-6640 3985);
FORCEPROP 1 LASTPIN (-6650 3975) BN 10
J 0
(-6662 3983);
DISPLAY 0.680851 (-6662 3983);
PAINT GREEN (-6662 3983);
FORCEPROP 2 LAST CDS_LIB standard
J 0
(-6600 3975);
DISPLAY INVISIBLE (-6600 3975);
FORCEPROP 1 LAST BODY_TYPE PLUMBING
J 0
(-6600 4025);
DISPLAY 0.872340 (-6600 4025);
PAINT GREEN (-6600 4025);
DISPLAY INVISIBLE (-6600 4025);
FORCEPROP 1 LAST HDL_TAP TRUE
J 0
(-6275 3850);
DISPLAY 0.872340 (-6275 3850);
DISPLAY INVISIBLE (-6275 3850);
FORCEPROP 1 LAST PATH I49
J 0
(-6602 3975);
DISPLAY 0.872340 (-6602 3975);
PAINT GREEN (-6602 3975);
DISPLAY INVISIBLE (-6602 3975);
FORCEADD TAP..1
R 2
(-3100 800);
FORCEPROP 3 LASTPIN (-3050 800) SIG_NAME P5E_CPU1_P1_TX_BUF_DP<7>
J 0
(-3040 810);
DISPLAY 0.659574 (-3040 810);
PAINT MONO (-3040 810);
DISPLAY INVISIBLE (-3040 810);
FORCEPROP 1 LASTPIN (-3050 800) BN 7
J 2
(-3038 808);
DISPLAY 0.680851 (-3038 808);
PAINT GREEN (-3038 808);
FORCEPROP 2 LAST CDS_LIB standard
J 0
(-3100 800);
DISPLAY INVISIBLE (-3100 800);
FORCEPROP 1 LAST BODY_TYPE PLUMBING
J 2
(-3100 850);
DISPLAY 0.872340 (-3100 850);
PAINT GREEN (-3100 850);
DISPLAY INVISIBLE (-3100 850);
FORCEPROP 1 LAST HDL_TAP TRUE
J 2
(-3425 675);
DISPLAY 0.872340 (-3425 675);
DISPLAY INVISIBLE (-3425 675);
FORCEPROP 1 LAST PATH I5
J 2
(-3098 800);
DISPLAY 0.872340 (-3098 800);
PAINT GREEN (-3098 800);
DISPLAY INVISIBLE (-3098 800);
FORCEADD TAP..1
(-1625 750);
FORCEPROP 3 LASTPIN (-1675 750) SIG_NAME P5E_CPU1_P1_TX_BUF_C_DN<7>
J 0
(-1665 760);
DISPLAY 0.659574 (-1665 760);
PAINT MONO (-1665 760);
DISPLAY INVISIBLE (-1665 760);
FORCEPROP 1 LASTPIN (-1675 750) BN 7
J 0
(-1687 758);
DISPLAY 0.680851 (-1687 758);
PAINT GREEN (-1687 758);
FORCEPROP 2 LAST CDS_LIB standard
J 0
(-1625 750);
DISPLAY INVISIBLE (-1625 750);
FORCEPROP 1 LAST BODY_TYPE PLUMBING
J 0
(-1625 800);
DISPLAY 0.872340 (-1625 800);
PAINT GREEN (-1625 800);
DISPLAY INVISIBLE (-1625 800);
FORCEPROP 1 LAST HDL_TAP TRUE
J 0
(-1300 625);
DISPLAY 0.872340 (-1300 625);
DISPLAY INVISIBLE (-1300 625);
FORCEPROP 1 LAST PATH I50
J 0
(-1627 750);
DISPLAY 0.872340 (-1627 750);
PAINT GREEN (-1627 750);
DISPLAY INVISIBLE (-1627 750);
FORCEADD TAP..1
(-1625 950);
FORCEPROP 3 LASTPIN (-1675 950) SIG_NAME P5E_CPU1_P1_TX_BUF_C_DN<6>
J 0
(-1665 960);
DISPLAY 0.659574 (-1665 960);
PAINT MONO (-1665 960);
DISPLAY INVISIBLE (-1665 960);
FORCEPROP 1 LASTPIN (-1675 950) BN 6
J 0
(-1687 958);
DISPLAY 0.680851 (-1687 958);
PAINT GREEN (-1687 958);
FORCEPROP 2 LAST CDS_LIB standard
J 0
(-1625 950);
DISPLAY INVISIBLE (-1625 950);
FORCEPROP 1 LAST BODY_TYPE PLUMBING
J 0
(-1625 1000);
DISPLAY 0.872340 (-1625 1000);
PAINT GREEN (-1625 1000);
DISPLAY INVISIBLE (-1625 1000);
FORCEPROP 1 LAST HDL_TAP TRUE
J 0
(-1300 825);
DISPLAY 0.872340 (-1300 825);
DISPLAY INVISIBLE (-1300 825);
FORCEPROP 1 LAST PATH I51
J 0
(-1627 950);
DISPLAY 0.872340 (-1627 950);
PAINT GREEN (-1627 950);
DISPLAY INVISIBLE (-1627 950);
FORCEADD TAP..1
(-1625 1150);
FORCEPROP 3 LASTPIN (-1675 1150) SIG_NAME P5E_CPU1_P1_TX_BUF_C_DN<5>
J 0
(-1665 1160);
DISPLAY 0.659574 (-1665 1160);
PAINT MONO (-1665 1160);
DISPLAY INVISIBLE (-1665 1160);
FORCEPROP 1 LASTPIN (-1675 1150) BN 5
J 0
(-1687 1158);
DISPLAY 0.680851 (-1687 1158);
PAINT GREEN (-1687 1158);
FORCEPROP 2 LAST CDS_LIB standard
J 0
(-1625 1150);
DISPLAY INVISIBLE (-1625 1150);
FORCEPROP 1 LAST BODY_TYPE PLUMBING
J 0
(-1625 1200);
DISPLAY 0.872340 (-1625 1200);
PAINT GREEN (-1625 1200);
DISPLAY INVISIBLE (-1625 1200);
FORCEPROP 1 LAST HDL_TAP TRUE
J 0
(-1300 1025);
DISPLAY 0.872340 (-1300 1025);
DISPLAY INVISIBLE (-1300 1025);
FORCEPROP 1 LAST PATH I52
J 0
(-1627 1150);
DISPLAY 0.872340 (-1627 1150);
PAINT GREEN (-1627 1150);
DISPLAY INVISIBLE (-1627 1150);
FORCEADD TAP..1
(-1625 1350);
FORCEPROP 3 LASTPIN (-1675 1350) SIG_NAME P5E_CPU1_P1_TX_BUF_C_DN<4>
J 0
(-1665 1360);
DISPLAY 0.659574 (-1665 1360);
PAINT MONO (-1665 1360);
DISPLAY INVISIBLE (-1665 1360);
FORCEPROP 1 LASTPIN (-1675 1350) BN 4
J 0
(-1687 1358);
DISPLAY 0.680851 (-1687 1358);
PAINT GREEN (-1687 1358);
FORCEPROP 2 LAST CDS_LIB standard
J 0
(-1625 1350);
DISPLAY INVISIBLE (-1625 1350);
FORCEPROP 1 LAST BODY_TYPE PLUMBING
J 0
(-1625 1400);
DISPLAY 0.872340 (-1625 1400);
PAINT GREEN (-1625 1400);
DISPLAY INVISIBLE (-1625 1400);
FORCEPROP 1 LAST HDL_TAP TRUE
J 0
(-1300 1225);
DISPLAY 0.872340 (-1300 1225);
DISPLAY INVISIBLE (-1300 1225);
FORCEPROP 1 LAST PATH I53
J 0
(-1627 1350);
DISPLAY 0.872340 (-1627 1350);
PAINT GREEN (-1627 1350);
DISPLAY INVISIBLE (-1627 1350);
FORCEADD TAP..1
(-1625 1550);
FORCEPROP 3 LASTPIN (-1675 1550) SIG_NAME P5E_CPU1_P1_TX_BUF_C_DN<3>
J 0
(-1665 1560);
DISPLAY 0.659574 (-1665 1560);
PAINT MONO (-1665 1560);
DISPLAY INVISIBLE (-1665 1560);
FORCEPROP 1 LASTPIN (-1675 1550) BN 3
J 0
(-1687 1558);
DISPLAY 0.680851 (-1687 1558);
PAINT GREEN (-1687 1558);
FORCEPROP 2 LAST CDS_LIB standard
J 0
(-1625 1550);
DISPLAY INVISIBLE (-1625 1550);
FORCEPROP 1 LAST BODY_TYPE PLUMBING
J 0
(-1625 1600);
DISPLAY 0.872340 (-1625 1600);
PAINT GREEN (-1625 1600);
DISPLAY INVISIBLE (-1625 1600);
FORCEPROP 1 LAST HDL_TAP TRUE
J 0
(-1300 1425);
DISPLAY 0.872340 (-1300 1425);
DISPLAY INVISIBLE (-1300 1425);
FORCEPROP 1 LAST PATH I54
J 0
(-1627 1550);
DISPLAY 0.872340 (-1627 1550);
PAINT GREEN (-1627 1550);
DISPLAY INVISIBLE (-1627 1550);
FORCEADD TAP..1
(-1625 1750);
FORCEPROP 3 LASTPIN (-1675 1750) SIG_NAME P5E_CPU1_P1_TX_BUF_C_DN<2>
J 0
(-1665 1760);
DISPLAY 0.659574 (-1665 1760);
PAINT MONO (-1665 1760);
DISPLAY INVISIBLE (-1665 1760);
FORCEPROP 1 LASTPIN (-1675 1750) BN 2
J 0
(-1687 1758);
DISPLAY 0.680851 (-1687 1758);
PAINT GREEN (-1687 1758);
FORCEPROP 2 LAST CDS_LIB standard
J 0
(-1625 1750);
DISPLAY INVISIBLE (-1625 1750);
FORCEPROP 1 LAST BODY_TYPE PLUMBING
J 0
(-1625 1800);
DISPLAY 0.872340 (-1625 1800);
PAINT GREEN (-1625 1800);
DISPLAY INVISIBLE (-1625 1800);
FORCEPROP 1 LAST HDL_TAP TRUE
J 0
(-1300 1625);
DISPLAY 0.872340 (-1300 1625);
DISPLAY INVISIBLE (-1300 1625);
FORCEPROP 1 LAST PATH I55
J 0
(-1627 1750);
DISPLAY 0.872340 (-1627 1750);
PAINT GREEN (-1627 1750);
DISPLAY INVISIBLE (-1627 1750);
FORCEADD TAP..1
(-1625 1950);
FORCEPROP 3 LASTPIN (-1675 1950) SIG_NAME P5E_CPU1_P1_TX_BUF_C_DN<1>
J 0
(-1665 1960);
DISPLAY 0.659574 (-1665 1960);
PAINT MONO (-1665 1960);
DISPLAY INVISIBLE (-1665 1960);
FORCEPROP 1 LASTPIN (-1675 1950) BN 1
J 0
(-1687 1958);
DISPLAY 0.680851 (-1687 1958);
PAINT GREEN (-1687 1958);
FORCEPROP 2 LAST CDS_LIB standard
J 0
(-1625 1950);
DISPLAY INVISIBLE (-1625 1950);
FORCEPROP 1 LAST BODY_TYPE PLUMBING
J 0
(-1625 2000);
DISPLAY 0.872340 (-1625 2000);
PAINT GREEN (-1625 2000);
DISPLAY INVISIBLE (-1625 2000);
FORCEPROP 1 LAST HDL_TAP TRUE
J 0
(-1300 1825);
DISPLAY 0.872340 (-1300 1825);
DISPLAY INVISIBLE (-1300 1825);
FORCEPROP 1 LAST PATH I56
J 0
(-1627 1950);
DISPLAY 0.872340 (-1627 1950);
PAINT GREEN (-1627 1950);
DISPLAY INVISIBLE (-1627 1950);
FORCEADD OFFPAGE..2
(-625 2175);
FORCEPROP 2 LAST $XR0 122 
J 0
(-436 2175);
DISPLAY 0.638298 (-436 2175);
PAINT MONO (-436 2175);
FORCEPROP 2 LAST CDS_LIB standard
J 0
(-625 2175);
DISPLAY INVISIBLE (-625 2175);
FORCEPROP 1 LAST OFFPAGE TRUE
J 0
(-300 2050);
DISPLAY 0.872340 (-300 2050);
DISPLAY INVISIBLE (-300 2050);
FORCEPROP 1 LAST COMMENT_BODY TRUE
J 0
(-670 2080);
DISPLAY 0.872340 (-670 2080);
PAINT GREEN (-670 2080);
DISPLAY INVISIBLE (-670 2080);
FORCEPROP 2 LAST PATH I57
J 0
(-425 2225);
DISPLAY 0.680851 (-425 2225);
DISPLAY INVISIBLE (-425 2225);
FORCEADD OFFPAGE..1
(-8925 2175);
FORCEPROP 2 LAST $XR0 331 
J 0
(-9207 2175);
DISPLAY 0.638298 (-9207 2175);
PAINT MONO (-9207 2175);
FORCEPROP 2 LAST CDS_LIB standard
J 0
(-8925 2175);
DISPLAY INVISIBLE (-8925 2175);
FORCEPROP 1 LAST OFFPAGE TRUE
J 0
(-8600 2050);
DISPLAY 0.872340 (-8600 2050);
DISPLAY INVISIBLE (-8600 2050);
FORCEPROP 1 LAST COMMENT_BODY TRUE
J 0
(-8800 2075);
DISPLAY 0.872340 (-8800 2075);
PAINT GREEN (-8800 2075);
DISPLAY INVISIBLE (-8800 2075);
FORCEPROP 2 LAST PATH I58
J 0
(-9175 2225);
DISPLAY 0.680851 (-9175 2225);
DISPLAY INVISIBLE (-9175 2225);
FORCEADD OFFPAGE..1
(-8925 2225);
FORCEPROP 2 LAST $XR0 331 
J 0
(-9207 2225);
DISPLAY 0.638298 (-9207 2225);
PAINT MONO (-9207 2225);
FORCEPROP 2 LAST CDS_LIB standard
J 0
(-8925 2225);
DISPLAY INVISIBLE (-8925 2225);
FORCEPROP 1 LAST OFFPAGE TRUE
J 0
(-8600 2100);
DISPLAY 0.872340 (-8600 2100);
DISPLAY INVISIBLE (-8600 2100);
FORCEPROP 1 LAST COMMENT_BODY TRUE
J 0
(-8800 2125);
DISPLAY 0.872340 (-8800 2125);
PAINT GREEN (-8800 2125);
DISPLAY INVISIBLE (-8800 2125);
FORCEPROP 2 LAST PATH I59
J 0
(-9175 2275);
DISPLAY 0.680851 (-9175 2275);
DISPLAY INVISIBLE (-9175 2275);
FORCEADD TAP..1
R 2
(-3100 1000);
FORCEPROP 3 LASTPIN (-3050 1000) SIG_NAME P5E_CPU1_P1_TX_BUF_DP<6>
J 0
(-3040 1010);
DISPLAY 0.659574 (-3040 1010);
PAINT MONO (-3040 1010);
DISPLAY INVISIBLE (-3040 1010);
FORCEPROP 1 LASTPIN (-3050 1000) BN 6
J 2
(-3038 1008);
DISPLAY 0.680851 (-3038 1008);
PAINT GREEN (-3038 1008);
FORCEPROP 2 LAST CDS_LIB standard
J 0
(-3100 1000);
DISPLAY INVISIBLE (-3100 1000);
FORCEPROP 1 LAST BODY_TYPE PLUMBING
J 2
(-3100 1050);
DISPLAY 0.872340 (-3100 1050);
PAINT GREEN (-3100 1050);
DISPLAY INVISIBLE (-3100 1050);
FORCEPROP 1 LAST HDL_TAP TRUE
J 2
(-3425 875);
DISPLAY 0.872340 (-3425 875);
DISPLAY INVISIBLE (-3425 875);
FORCEPROP 1 LAST PATH I6
J 2
(-3098 1000);
DISPLAY 0.872340 (-3098 1000);
PAINT GREEN (-3098 1000);
DISPLAY INVISIBLE (-3098 1000);
FORCEADD TAP..1
(-1625 2150);
FORCEPROP 3 LASTPIN (-1675 2150) SIG_NAME P5E_CPU1_P1_TX_BUF_C_DN<0>
J 0
(-1665 2160);
DISPLAY 0.659574 (-1665 2160);
PAINT MONO (-1665 2160);
DISPLAY INVISIBLE (-1665 2160);
FORCEPROP 1 LASTPIN (-1675 2150) BN 0
J 0
(-1687 2158);
DISPLAY 0.680851 (-1687 2158);
PAINT GREEN (-1687 2158);
FORCEPROP 2 LAST CDS_LIB standard
J 0
(-1625 2150);
DISPLAY INVISIBLE (-1625 2150);
FORCEPROP 1 LAST BODY_TYPE PLUMBING
J 0
(-1625 2200);
DISPLAY 0.872340 (-1625 2200);
PAINT GREEN (-1625 2200);
DISPLAY INVISIBLE (-1625 2200);
FORCEPROP 1 LAST HDL_TAP TRUE
J 0
(-1300 2025);
DISPLAY 0.872340 (-1300 2025);
DISPLAY INVISIBLE (-1300 2025);
FORCEPROP 1 LAST PATH I60
J 0
(-1627 2150);
DISPLAY 0.872340 (-1627 2150);
PAINT GREEN (-1627 2150);
DISPLAY INVISIBLE (-1627 2150);
FORCEADD OFFPAGE..2
(-625 2225);
FORCEPROP 2 LAST $XR0 122 
J 0
(-436 2225);
DISPLAY 0.638298 (-436 2225);
PAINT MONO (-436 2225);
FORCEPROP 2 LAST CDS_LIB standard
J 0
(-625 2225);
DISPLAY INVISIBLE (-625 2225);
FORCEPROP 1 LAST OFFPAGE TRUE
J 0
(-300 2100);
DISPLAY 0.872340 (-300 2100);
DISPLAY INVISIBLE (-300 2100);
FORCEPROP 1 LAST COMMENT_BODY TRUE
J 0
(-670 2130);
DISPLAY 0.872340 (-670 2130);
PAINT GREEN (-670 2130);
DISPLAY INVISIBLE (-670 2130);
FORCEPROP 2 LAST PATH I61
J 0
(-425 2275);
DISPLAY 0.680851 (-425 2275);
DISPLAY INVISIBLE (-425 2275);
FORCEADD TAP..1
(-6800 4425);
FORCEPROP 3 LASTPIN (-6850 4425) SIG_NAME P5E_CPU1_P1_TX_BUF_DP<11>
J 0
(-6840 4435);
DISPLAY 0.659574 (-6840 4435);
PAINT MONO (-6840 4435);
DISPLAY INVISIBLE (-6840 4435);
FORCEPROP 1 LASTPIN (-6850 4425) BN 11
J 0
(-6862 4433);
DISPLAY 0.680851 (-6862 4433);
PAINT GREEN (-6862 4433);
FORCEPROP 2 LAST CDS_LIB standard
J 0
(-6800 4425);
DISPLAY INVISIBLE (-6800 4425);
FORCEPROP 1 LAST BODY_TYPE PLUMBING
J 0
(-6800 4475);
DISPLAY 0.872340 (-6800 4475);
PAINT GREEN (-6800 4475);
DISPLAY INVISIBLE (-6800 4475);
FORCEPROP 1 LAST HDL_TAP TRUE
J 0
(-6475 4300);
DISPLAY 0.872340 (-6475 4300);
DISPLAY INVISIBLE (-6475 4300);
FORCEPROP 1 LAST PATH I62
J 0
(-6802 4425);
DISPLAY 0.872340 (-6802 4425);
PAINT GREEN (-6802 4425);
DISPLAY INVISIBLE (-6802 4425);
FORCEADD TAP..1
(-6600 4325);
FORCEPROP 3 LASTPIN (-6650 4325) SIG_NAME P5E_CPU1_P1_TX_BUF_DN<11>
J 0
(-6640 4335);
DISPLAY 0.659574 (-6640 4335);
PAINT MONO (-6640 4335);
DISPLAY INVISIBLE (-6640 4335);
FORCEPROP 1 LASTPIN (-6650 4325) BN 11
J 0
(-6662 4333);
DISPLAY 0.680851 (-6662 4333);
PAINT GREEN (-6662 4333);
FORCEPROP 2 LAST CDS_LIB standard
J 0
(-6600 4325);
DISPLAY INVISIBLE (-6600 4325);
FORCEPROP 1 LAST BODY_TYPE PLUMBING
J 0
(-6600 4375);
DISPLAY 0.872340 (-6600 4375);
PAINT GREEN (-6600 4375);
DISPLAY INVISIBLE (-6600 4375);
FORCEPROP 1 LAST HDL_TAP TRUE
J 0
(-6275 4200);
DISPLAY 0.872340 (-6275 4200);
DISPLAY INVISIBLE (-6275 4200);
FORCEPROP 1 LAST PATH I63
J 0
(-6602 4325);
DISPLAY 0.872340 (-6602 4325);
PAINT GREEN (-6602 4325);
DISPLAY INVISIBLE (-6602 4325);
FORCEADD TAP..1
(-6600 4675);
FORCEPROP 3 LASTPIN (-6650 4675) SIG_NAME P5E_CPU1_P1_TX_BUF_DN<12>
J 0
(-6640 4685);
DISPLAY 0.659574 (-6640 4685);
PAINT MONO (-6640 4685);
DISPLAY INVISIBLE (-6640 4685);
FORCEPROP 1 LASTPIN (-6650 4675) BN 12
J 0
(-6662 4683);
DISPLAY 0.680851 (-6662 4683);
PAINT GREEN (-6662 4683);
FORCEPROP 2 LAST CDS_LIB standard
J 0
(-6600 4675);
DISPLAY INVISIBLE (-6600 4675);
FORCEPROP 1 LAST BODY_TYPE PLUMBING
J 0
(-6600 4725);
DISPLAY 0.872340 (-6600 4725);
PAINT GREEN (-6600 4725);
DISPLAY INVISIBLE (-6600 4725);
FORCEPROP 1 LAST HDL_TAP TRUE
J 0
(-6275 4550);
DISPLAY 0.872340 (-6275 4550);
DISPLAY INVISIBLE (-6275 4550);
FORCEPROP 1 LAST PATH I64
J 0
(-6602 4675);
DISPLAY 0.872340 (-6602 4675);
PAINT GREEN (-6602 4675);
DISPLAY INVISIBLE (-6602 4675);
FORCEADD TAP..1
(-6800 4775);
FORCEPROP 3 LASTPIN (-6850 4775) SIG_NAME P5E_CPU1_P1_TX_BUF_DP<12>
J 0
(-6840 4785);
DISPLAY 0.659574 (-6840 4785);
PAINT MONO (-6840 4785);
DISPLAY INVISIBLE (-6840 4785);
FORCEPROP 1 LASTPIN (-6850 4775) BN 12
J 0
(-6862 4783);
DISPLAY 0.680851 (-6862 4783);
PAINT GREEN (-6862 4783);
FORCEPROP 2 LAST CDS_LIB standard
J 0
(-6800 4775);
DISPLAY INVISIBLE (-6800 4775);
FORCEPROP 1 LAST BODY_TYPE PLUMBING
J 0
(-6800 4825);
DISPLAY 0.872340 (-6800 4825);
PAINT GREEN (-6800 4825);
DISPLAY INVISIBLE (-6800 4825);
FORCEPROP 1 LAST HDL_TAP TRUE
J 0
(-6475 4650);
DISPLAY 0.872340 (-6475 4650);
DISPLAY INVISIBLE (-6475 4650);
FORCEPROP 1 LAST PATH I65
J 0
(-6802 4775);
DISPLAY 0.872340 (-6802 4775);
PAINT GREEN (-6802 4775);
DISPLAY INVISIBLE (-6802 4775);
FORCEADD TAP..1
(-6800 5125);
FORCEPROP 3 LASTPIN (-6850 5125) SIG_NAME P5E_CPU1_P1_TX_BUF_DP<13>
J 0
(-6840 5135);
DISPLAY 0.659574 (-6840 5135);
PAINT MONO (-6840 5135);
DISPLAY INVISIBLE (-6840 5135);
FORCEPROP 1 LASTPIN (-6850 5125) BN 13
J 0
(-6862 5133);
DISPLAY 0.680851 (-6862 5133);
PAINT GREEN (-6862 5133);
FORCEPROP 2 LAST CDS_LIB standard
J 0
(-6800 5125);
DISPLAY INVISIBLE (-6800 5125);
FORCEPROP 1 LAST BODY_TYPE PLUMBING
J 0
(-6800 5175);
DISPLAY 0.872340 (-6800 5175);
PAINT GREEN (-6800 5175);
DISPLAY INVISIBLE (-6800 5175);
FORCEPROP 1 LAST HDL_TAP TRUE
J 0
(-6475 5000);
DISPLAY 0.872340 (-6475 5000);
DISPLAY INVISIBLE (-6475 5000);
FORCEPROP 1 LAST PATH I66
J 0
(-6802 5125);
DISPLAY 0.872340 (-6802 5125);
PAINT GREEN (-6802 5125);
DISPLAY INVISIBLE (-6802 5125);
FORCEADD TAP..1
(-6600 5025);
FORCEPROP 3 LASTPIN (-6650 5025) SIG_NAME P5E_CPU1_P1_TX_BUF_DN<13>
J 0
(-6640 5035);
DISPLAY 0.659574 (-6640 5035);
PAINT MONO (-6640 5035);
DISPLAY INVISIBLE (-6640 5035);
FORCEPROP 1 LASTPIN (-6650 5025) BN 13
J 0
(-6662 5033);
DISPLAY 0.680851 (-6662 5033);
PAINT GREEN (-6662 5033);
FORCEPROP 2 LAST CDS_LIB standard
J 0
(-6600 5025);
DISPLAY INVISIBLE (-6600 5025);
FORCEPROP 1 LAST BODY_TYPE PLUMBING
J 0
(-6600 5075);
DISPLAY 0.872340 (-6600 5075);
PAINT GREEN (-6600 5075);
DISPLAY INVISIBLE (-6600 5075);
FORCEPROP 1 LAST HDL_TAP TRUE
J 0
(-6275 4900);
DISPLAY 0.872340 (-6275 4900);
DISPLAY INVISIBLE (-6275 4900);
FORCEPROP 1 LAST PATH I67
J 0
(-6602 5025);
DISPLAY 0.872340 (-6602 5025);
PAINT GREEN (-6602 5025);
DISPLAY INVISIBLE (-6602 5025);
FORCEADD TAP..1
(-6800 5475);
FORCEPROP 3 LASTPIN (-6850 5475) SIG_NAME P5E_CPU1_P1_TX_BUF_DP<14>
J 0
(-6840 5485);
DISPLAY 0.659574 (-6840 5485);
PAINT MONO (-6840 5485);
DISPLAY INVISIBLE (-6840 5485);
FORCEPROP 1 LASTPIN (-6850 5475) BN 14
J 0
(-6862 5483);
DISPLAY 0.680851 (-6862 5483);
PAINT GREEN (-6862 5483);
FORCEPROP 2 LAST CDS_LIB standard
J 0
(-6800 5475);
DISPLAY INVISIBLE (-6800 5475);
FORCEPROP 1 LAST BODY_TYPE PLUMBING
J 0
(-6800 5525);
DISPLAY 0.872340 (-6800 5525);
PAINT GREEN (-6800 5525);
DISPLAY INVISIBLE (-6800 5525);
FORCEPROP 1 LAST HDL_TAP TRUE
J 0
(-6475 5350);
DISPLAY 0.872340 (-6475 5350);
DISPLAY INVISIBLE (-6475 5350);
FORCEPROP 1 LAST PATH I68
J 0
(-6802 5475);
DISPLAY 0.872340 (-6802 5475);
PAINT GREEN (-6802 5475);
DISPLAY INVISIBLE (-6802 5475);
FORCEADD TAP..1
(-6600 5375);
FORCEPROP 3 LASTPIN (-6650 5375) SIG_NAME P5E_CPU1_P1_TX_BUF_DN<14>
J 0
(-6640 5385);
DISPLAY 0.659574 (-6640 5385);
PAINT MONO (-6640 5385);
DISPLAY INVISIBLE (-6640 5385);
FORCEPROP 1 LASTPIN (-6650 5375) BN 14
J 0
(-6662 5383);
DISPLAY 0.680851 (-6662 5383);
PAINT GREEN (-6662 5383);
FORCEPROP 2 LAST CDS_LIB standard
J 0
(-6600 5375);
DISPLAY INVISIBLE (-6600 5375);
FORCEPROP 1 LAST BODY_TYPE PLUMBING
J 0
(-6600 5425);
DISPLAY 0.872340 (-6600 5425);
PAINT GREEN (-6600 5425);
DISPLAY INVISIBLE (-6600 5425);
FORCEPROP 1 LAST HDL_TAP TRUE
J 0
(-6275 5250);
DISPLAY 0.872340 (-6275 5250);
DISPLAY INVISIBLE (-6275 5250);
FORCEPROP 1 LAST PATH I69
J 0
(-6602 5375);
DISPLAY 0.872340 (-6602 5375);
PAINT GREEN (-6602 5375);
DISPLAY INVISIBLE (-6602 5375);
FORCEADD TAP..1
R 2
(-3350 1150);
FORCEPROP 3 LASTPIN (-3300 1150) SIG_NAME P5E_CPU1_P1_TX_BUF_DN<5>
J 0
(-3290 1160);
DISPLAY 0.659574 (-3290 1160);
PAINT MONO (-3290 1160);
DISPLAY INVISIBLE (-3290 1160);
FORCEPROP 1 LASTPIN (-3300 1150) BN 5
J 2
(-3288 1158);
DISPLAY 0.680851 (-3288 1158);
PAINT GREEN (-3288 1158);
FORCEPROP 2 LAST CDS_LIB standard
J 0
(-3350 1150);
DISPLAY INVISIBLE (-3350 1150);
FORCEPROP 1 LAST BODY_TYPE PLUMBING
J 2
(-3350 1200);
DISPLAY 0.872340 (-3350 1200);
PAINT GREEN (-3350 1200);
DISPLAY INVISIBLE (-3350 1200);
FORCEPROP 1 LAST HDL_TAP TRUE
J 2
(-3675 1025);
DISPLAY 0.872340 (-3675 1025);
DISPLAY INVISIBLE (-3675 1025);
FORCEPROP 1 LAST PATH I7
J 2
(-3348 1150);
DISPLAY 0.872340 (-3348 1150);
PAINT GREEN (-3348 1150);
DISPLAY INVISIBLE (-3348 1150);
FORCEADD TAP..1
(-6600 5725);
FORCEPROP 3 LASTPIN (-6650 5725) SIG_NAME P5E_CPU1_P1_TX_BUF_DN<15>
J 0
(-6640 5735);
DISPLAY 0.659574 (-6640 5735);
PAINT MONO (-6640 5735);
DISPLAY INVISIBLE (-6640 5735);
FORCEPROP 1 LASTPIN (-6650 5725) BN 15
J 0
(-6662 5733);
DISPLAY 0.680851 (-6662 5733);
PAINT GREEN (-6662 5733);
FORCEPROP 2 LAST CDS_LIB standard
J 0
(-6600 5725);
DISPLAY INVISIBLE (-6600 5725);
FORCEPROP 1 LAST BODY_TYPE PLUMBING
J 0
(-6600 5775);
DISPLAY 0.872340 (-6600 5775);
PAINT GREEN (-6600 5775);
DISPLAY INVISIBLE (-6600 5775);
FORCEPROP 1 LAST HDL_TAP TRUE
J 0
(-6275 5600);
DISPLAY 0.872340 (-6275 5600);
DISPLAY INVISIBLE (-6275 5600);
FORCEPROP 1 LAST PATH I70
J 0
(-6602 5725);
DISPLAY 0.872340 (-6602 5725);
PAINT GREEN (-6602 5725);
DISPLAY INVISIBLE (-6602 5725);
FORCEADD TAP..1
(-6800 5825);
FORCEPROP 3 LASTPIN (-6850 5825) SIG_NAME P5E_CPU1_P1_TX_BUF_DP<15>
J 0
(-6840 5835);
DISPLAY 0.659574 (-6840 5835);
PAINT MONO (-6840 5835);
DISPLAY INVISIBLE (-6840 5835);
FORCEPROP 1 LASTPIN (-6850 5825) BN 15
J 0
(-6862 5833);
DISPLAY 0.680851 (-6862 5833);
PAINT GREEN (-6862 5833);
FORCEPROP 2 LAST CDS_LIB standard
J 0
(-6800 5825);
DISPLAY INVISIBLE (-6800 5825);
FORCEPROP 1 LAST BODY_TYPE PLUMBING
J 0
(-6800 5875);
DISPLAY 0.872340 (-6800 5875);
PAINT GREEN (-6800 5875);
DISPLAY INVISIBLE (-6800 5875);
FORCEPROP 1 LAST HDL_TAP TRUE
J 0
(-6475 5700);
DISPLAY 0.872340 (-6475 5700);
DISPLAY INVISIBLE (-6475 5700);
FORCEPROP 1 LAST PATH I71
J 0
(-6802 5825);
DISPLAY 0.872340 (-6802 5825);
PAINT GREEN (-6802 5825);
DISPLAY INVISIBLE (-6802 5825);
FORCEADD OFFPAGE..5
R 2
(-5625 5750);
FORCEPROP 2 LAST $XR0 331 
J 0
(-5436 5750);
DISPLAY 0.638298 (-5436 5750);
PAINT MONO (-5436 5750);
FORCEPROP 2 LAST CDS_LIB standard
J 0
(-5625 5750);
DISPLAY INVISIBLE (-5625 5750);
FORCEPROP 1 LAST OFFPAGE TRUE
J 2
(-5950 5625);
DISPLAY 0.872340 (-5950 5625);
PAINT GREEN (-5950 5625);
DISPLAY INVISIBLE (-5950 5625);
FORCEPROP 1 LAST COMMENT_BODY TRUE
J 2
(-5725 5675);
DISPLAY 0.872340 (-5725 5675);
PAINT GREEN (-5725 5675);
DISPLAY INVISIBLE (-5725 5675);
FORCEPROP 2 LAST PATH I72
J 0
(-5450 5825);
DISPLAY 0.680851 (-5450 5825);
DISPLAY INVISIBLE (-5450 5825);
FORCEADD OFFPAGE..5
R 2
(-5600 5850);
FORCEPROP 2 LAST $XR0 331 
J 0
(-5411 5850);
DISPLAY 0.638298 (-5411 5850);
PAINT MONO (-5411 5850);
FORCEPROP 2 LAST CDS_LIB standard
J 0
(-5600 5850);
DISPLAY INVISIBLE (-5600 5850);
FORCEPROP 1 LAST OFFPAGE TRUE
J 2
(-5925 5725);
DISPLAY 0.872340 (-5925 5725);
PAINT GREEN (-5925 5725);
DISPLAY INVISIBLE (-5925 5725);
FORCEPROP 1 LAST COMMENT_BODY TRUE
J 2
(-5700 5775);
DISPLAY 0.872340 (-5700 5775);
PAINT GREEN (-5700 5775);
DISPLAY INVISIBLE (-5700 5775);
FORCEPROP 2 LAST PATH I73
J 0
(-5425 5925);
DISPLAY 0.680851 (-5425 5925);
DISPLAY INVISIBLE (-5425 5925);
FORCEADD TAP..1
R 2
(-7975 750);
FORCEPROP 3 LASTPIN (-7925 750) SIG_NAME P5E_CPU1_P1_TX_BUF_DN<15>
J 0
(-7915 760);
DISPLAY 0.659574 (-7915 760);
PAINT MONO (-7915 760);
DISPLAY INVISIBLE (-7915 760);
FORCEPROP 1 LASTPIN (-7925 750) BN 15
J 2
(-7913 758);
DISPLAY 0.680851 (-7913 758);
PAINT GREEN (-7913 758);
FORCEPROP 2 LAST CDS_LIB standard
J 0
(-7975 750);
DISPLAY INVISIBLE (-7975 750);
FORCEPROP 1 LAST BODY_TYPE PLUMBING
J 2
(-7975 800);
DISPLAY 0.872340 (-7975 800);
PAINT GREEN (-7975 800);
DISPLAY INVISIBLE (-7975 800);
FORCEPROP 1 LAST HDL_TAP TRUE
J 2
(-8300 625);
DISPLAY 0.872340 (-8300 625);
DISPLAY INVISIBLE (-8300 625);
FORCEPROP 1 LAST PATH I74
J 2
(-7973 750);
DISPLAY 0.872340 (-7973 750);
PAINT GREEN (-7973 750);
DISPLAY INVISIBLE (-7973 750);
FORCEADD TAP..1
R 2
(-7975 950);
FORCEPROP 3 LASTPIN (-7925 950) SIG_NAME P5E_CPU1_P1_TX_BUF_DN<14>
J 0
(-7915 960);
DISPLAY 0.659574 (-7915 960);
PAINT MONO (-7915 960);
DISPLAY INVISIBLE (-7915 960);
FORCEPROP 1 LASTPIN (-7925 950) BN 14
J 2
(-7913 958);
DISPLAY 0.680851 (-7913 958);
PAINT GREEN (-7913 958);
FORCEPROP 2 LAST CDS_LIB standard
J 0
(-7975 950);
DISPLAY INVISIBLE (-7975 950);
FORCEPROP 1 LAST BODY_TYPE PLUMBING
J 2
(-7975 1000);
DISPLAY 0.872340 (-7975 1000);
PAINT GREEN (-7975 1000);
DISPLAY INVISIBLE (-7975 1000);
FORCEPROP 1 LAST HDL_TAP TRUE
J 2
(-8300 825);
DISPLAY 0.872340 (-8300 825);
DISPLAY INVISIBLE (-8300 825);
FORCEPROP 1 LAST PATH I75
J 2
(-7973 950);
DISPLAY 0.872340 (-7973 950);
PAINT GREEN (-7973 950);
DISPLAY INVISIBLE (-7973 950);
FORCEADD TAP..1
R 2
(-7975 1150);
FORCEPROP 3 LASTPIN (-7925 1150) SIG_NAME P5E_CPU1_P1_TX_BUF_DN<13>
J 0
(-7915 1160);
DISPLAY 0.659574 (-7915 1160);
PAINT MONO (-7915 1160);
DISPLAY INVISIBLE (-7915 1160);
FORCEPROP 1 LASTPIN (-7925 1150) BN 13
J 2
(-7913 1158);
DISPLAY 0.680851 (-7913 1158);
PAINT GREEN (-7913 1158);
FORCEPROP 2 LAST CDS_LIB standard
J 0
(-7975 1150);
DISPLAY INVISIBLE (-7975 1150);
FORCEPROP 1 LAST BODY_TYPE PLUMBING
J 2
(-7975 1200);
DISPLAY 0.872340 (-7975 1200);
PAINT GREEN (-7975 1200);
DISPLAY INVISIBLE (-7975 1200);
FORCEPROP 1 LAST HDL_TAP TRUE
J 2
(-8300 1025);
DISPLAY 0.872340 (-8300 1025);
DISPLAY INVISIBLE (-8300 1025);
FORCEPROP 1 LAST PATH I76
J 2
(-7973 1150);
DISPLAY 0.872340 (-7973 1150);
PAINT GREEN (-7973 1150);
DISPLAY INVISIBLE (-7973 1150);
FORCEADD TAP..1
R 2
(-7975 1350);
FORCEPROP 3 LASTPIN (-7925 1350) SIG_NAME P5E_CPU1_P1_TX_BUF_DN<12>
J 0
(-7915 1360);
DISPLAY 0.659574 (-7915 1360);
PAINT MONO (-7915 1360);
DISPLAY INVISIBLE (-7915 1360);
FORCEPROP 1 LASTPIN (-7925 1350) BN 12
J 2
(-7913 1358);
DISPLAY 0.680851 (-7913 1358);
PAINT GREEN (-7913 1358);
FORCEPROP 2 LAST CDS_LIB standard
J 0
(-7975 1350);
DISPLAY INVISIBLE (-7975 1350);
FORCEPROP 1 LAST BODY_TYPE PLUMBING
J 2
(-7975 1400);
DISPLAY 0.872340 (-7975 1400);
PAINT GREEN (-7975 1400);
DISPLAY INVISIBLE (-7975 1400);
FORCEPROP 1 LAST HDL_TAP TRUE
J 2
(-8300 1225);
DISPLAY 0.872340 (-8300 1225);
DISPLAY INVISIBLE (-8300 1225);
FORCEPROP 1 LAST PATH I77
J 2
(-7973 1350);
DISPLAY 0.872340 (-7973 1350);
PAINT GREEN (-7973 1350);
DISPLAY INVISIBLE (-7973 1350);
FORCEADD TAP..1
R 2
(-7975 1550);
FORCEPROP 3 LASTPIN (-7925 1550) SIG_NAME P5E_CPU1_P1_TX_BUF_DN<11>
J 0
(-7915 1560);
DISPLAY 0.659574 (-7915 1560);
PAINT MONO (-7915 1560);
DISPLAY INVISIBLE (-7915 1560);
FORCEPROP 1 LASTPIN (-7925 1550) BN 11
J 2
(-7913 1558);
DISPLAY 0.680851 (-7913 1558);
PAINT GREEN (-7913 1558);
FORCEPROP 2 LAST CDS_LIB standard
J 0
(-7975 1550);
DISPLAY INVISIBLE (-7975 1550);
FORCEPROP 1 LAST BODY_TYPE PLUMBING
J 2
(-7975 1600);
DISPLAY 0.872340 (-7975 1600);
PAINT GREEN (-7975 1600);
DISPLAY INVISIBLE (-7975 1600);
FORCEPROP 1 LAST HDL_TAP TRUE
J 2
(-8300 1425);
DISPLAY 0.872340 (-8300 1425);
DISPLAY INVISIBLE (-8300 1425);
FORCEPROP 1 LAST PATH I78
J 2
(-7973 1550);
DISPLAY 0.872340 (-7973 1550);
PAINT GREEN (-7973 1550);
DISPLAY INVISIBLE (-7973 1550);
FORCEADD TAP..1
R 2
(-7975 1750);
FORCEPROP 3 LASTPIN (-7925 1750) SIG_NAME P5E_CPU1_P1_TX_BUF_DN<10>
J 0
(-7915 1760);
DISPLAY 0.659574 (-7915 1760);
PAINT MONO (-7915 1760);
DISPLAY INVISIBLE (-7915 1760);
FORCEPROP 1 LASTPIN (-7925 1750) BN 10
J 2
(-7913 1758);
DISPLAY 0.680851 (-7913 1758);
PAINT GREEN (-7913 1758);
FORCEPROP 2 LAST CDS_LIB standard
J 0
(-7975 1750);
DISPLAY INVISIBLE (-7975 1750);
FORCEPROP 1 LAST BODY_TYPE PLUMBING
J 2
(-7975 1800);
DISPLAY 0.872340 (-7975 1800);
PAINT GREEN (-7975 1800);
DISPLAY INVISIBLE (-7975 1800);
FORCEPROP 1 LAST HDL_TAP TRUE
J 2
(-8300 1625);
DISPLAY 0.872340 (-8300 1625);
DISPLAY INVISIBLE (-8300 1625);
FORCEPROP 1 LAST PATH I79
J 2
(-7973 1750);
DISPLAY 0.872340 (-7973 1750);
PAINT GREEN (-7973 1750);
DISPLAY INVISIBLE (-7973 1750);
FORCEADD TAP..1
R 2
(-3350 1350);
FORCEPROP 3 LASTPIN (-3300 1350) SIG_NAME P5E_CPU1_P1_TX_BUF_DN<4>
J 0
(-3290 1360);
DISPLAY 0.659574 (-3290 1360);
PAINT MONO (-3290 1360);
DISPLAY INVISIBLE (-3290 1360);
FORCEPROP 1 LASTPIN (-3300 1350) BN 4
J 2
(-3288 1358);
DISPLAY 0.680851 (-3288 1358);
PAINT GREEN (-3288 1358);
FORCEPROP 2 LAST CDS_LIB standard
J 0
(-3350 1350);
DISPLAY INVISIBLE (-3350 1350);
FORCEPROP 1 LAST BODY_TYPE PLUMBING
J 2
(-3350 1400);
DISPLAY 0.872340 (-3350 1400);
PAINT GREEN (-3350 1400);
DISPLAY INVISIBLE (-3350 1400);
FORCEPROP 1 LAST HDL_TAP TRUE
J 2
(-3675 1225);
DISPLAY 0.872340 (-3675 1225);
DISPLAY INVISIBLE (-3675 1225);
FORCEPROP 1 LAST PATH I8
J 2
(-3348 1350);
DISPLAY 0.872340 (-3348 1350);
PAINT GREEN (-3348 1350);
DISPLAY INVISIBLE (-3348 1350);
FORCEADD TAP..1
R 2
(-7975 1950);
FORCEPROP 3 LASTPIN (-7925 1950) SIG_NAME P5E_CPU1_P1_TX_BUF_DN<9>
J 0
(-7915 1960);
DISPLAY 0.659574 (-7915 1960);
PAINT MONO (-7915 1960);
DISPLAY INVISIBLE (-7915 1960);
FORCEPROP 1 LASTPIN (-7925 1950) BN 9
J 2
(-7913 1958);
DISPLAY 0.680851 (-7913 1958);
PAINT GREEN (-7913 1958);
FORCEPROP 2 LAST CDS_LIB standard
J 0
(-7975 1950);
DISPLAY INVISIBLE (-7975 1950);
FORCEPROP 1 LAST BODY_TYPE PLUMBING
J 2
(-7975 2000);
DISPLAY 0.872340 (-7975 2000);
PAINT GREEN (-7975 2000);
DISPLAY INVISIBLE (-7975 2000);
FORCEPROP 1 LAST HDL_TAP TRUE
J 2
(-8300 1825);
DISPLAY 0.872340 (-8300 1825);
DISPLAY INVISIBLE (-8300 1825);
FORCEPROP 1 LAST PATH I80
J 2
(-7973 1950);
DISPLAY 0.872340 (-7973 1950);
PAINT GREEN (-7973 1950);
DISPLAY INVISIBLE (-7973 1950);
FORCEADD TAP..1
R 2
(-7975 2150);
FORCEPROP 3 LASTPIN (-7925 2150) SIG_NAME P5E_CPU1_P1_TX_BUF_DN<8>
J 0
(-7915 2160);
DISPLAY 0.659574 (-7915 2160);
PAINT MONO (-7915 2160);
DISPLAY INVISIBLE (-7915 2160);
FORCEPROP 1 LASTPIN (-7925 2150) BN 8
J 2
(-7913 2158);
DISPLAY 0.680851 (-7913 2158);
PAINT GREEN (-7913 2158);
FORCEPROP 2 LAST CDS_LIB standard
J 0
(-7975 2150);
DISPLAY INVISIBLE (-7975 2150);
FORCEPROP 1 LAST BODY_TYPE PLUMBING
J 2
(-7975 2200);
DISPLAY 0.872340 (-7975 2200);
PAINT GREEN (-7975 2200);
DISPLAY INVISIBLE (-7975 2200);
FORCEPROP 1 LAST HDL_TAP TRUE
J 2
(-8300 2025);
DISPLAY 0.872340 (-8300 2025);
DISPLAY INVISIBLE (-8300 2025);
FORCEPROP 1 LAST PATH I81
J 2
(-7973 2150);
DISPLAY 0.872340 (-7973 2150);
PAINT GREEN (-7973 2150);
DISPLAY INVISIBLE (-7973 2150);
FORCEADD TAP..1
R 2
(-7725 800);
FORCEPROP 3 LASTPIN (-7675 800) SIG_NAME P5E_CPU1_P1_TX_BUF_DP<15>
J 0
(-7665 810);
DISPLAY 0.659574 (-7665 810);
PAINT MONO (-7665 810);
DISPLAY INVISIBLE (-7665 810);
FORCEPROP 1 LASTPIN (-7675 800) BN 15
J 2
(-7663 808);
DISPLAY 0.680851 (-7663 808);
PAINT GREEN (-7663 808);
FORCEPROP 2 LAST CDS_LIB standard
J 0
(-7725 800);
DISPLAY INVISIBLE (-7725 800);
FORCEPROP 1 LAST BODY_TYPE PLUMBING
J 2
(-7725 850);
DISPLAY 0.872340 (-7725 850);
PAINT GREEN (-7725 850);
DISPLAY INVISIBLE (-7725 850);
FORCEPROP 1 LAST HDL_TAP TRUE
J 2
(-8050 675);
DISPLAY 0.872340 (-8050 675);
DISPLAY INVISIBLE (-8050 675);
FORCEPROP 1 LAST PATH I82
J 2
(-7723 800);
DISPLAY 0.872340 (-7723 800);
PAINT GREEN (-7723 800);
DISPLAY INVISIBLE (-7723 800);
FORCEADD TAP..1
R 2
(-7725 1000);
FORCEPROP 3 LASTPIN (-7675 1000) SIG_NAME P5E_CPU1_P1_TX_BUF_DP<14>
J 0
(-7665 1010);
DISPLAY 0.659574 (-7665 1010);
PAINT MONO (-7665 1010);
DISPLAY INVISIBLE (-7665 1010);
FORCEPROP 1 LASTPIN (-7675 1000) BN 14
J 2
(-7663 1008);
DISPLAY 0.680851 (-7663 1008);
PAINT GREEN (-7663 1008);
FORCEPROP 2 LAST CDS_LIB standard
J 0
(-7725 1000);
DISPLAY INVISIBLE (-7725 1000);
FORCEPROP 1 LAST BODY_TYPE PLUMBING
J 2
(-7725 1050);
DISPLAY 0.872340 (-7725 1050);
PAINT GREEN (-7725 1050);
DISPLAY INVISIBLE (-7725 1050);
FORCEPROP 1 LAST HDL_TAP TRUE
J 2
(-8050 875);
DISPLAY 0.872340 (-8050 875);
DISPLAY INVISIBLE (-8050 875);
FORCEPROP 1 LAST PATH I83
J 2
(-7723 1000);
DISPLAY 0.872340 (-7723 1000);
PAINT GREEN (-7723 1000);
DISPLAY INVISIBLE (-7723 1000);
FORCEADD Q_CAP_DIFFBUS..2
R 2
(-7000 750);
FORCEPROP 1 LAST LOCATION C6692
J 2
(-6725 750);
DISPLAY 0.723404 (-6725 750);
PAINT GREEN (-6725 750);
FORCEPROP 2 LAST $SEC 1
J 2
(-6825 825);
DISPLAY 0.680851 (-6825 825);
PAINT MONO (-6825 825);
DISPLAY INVISIBLE (-6825 825);
FORCEPROP 2 LAST CDS_SEC 1
J 2
(-6825 825);
DISPLAY 0.680851 (-6825 825);
DISPLAY INVISIBLE (-6825 825);
FORCEPROP 2 LASTPIN (-6925 750) $PN 1
J 0
(-6915 760);
DISPLAY 0.808511 (-6915 760);
FORCEPROP 2 LASTPIN (-7075 750) $PN 2
J 2
(-7085 760);
DISPLAY 0.808511 (-7085 760);
FORCEPROP 2 LAST VALUE DIFF BUS_0.22UF
J 2
(-7150 750);
DISPLAY 0.553191 (-7150 750);
FORCEPROP 2 LAST TOLERANCE 20%
J 2
(-7075 800);
DISPLAY 0.553191 (-7075 800);
DISPLAY INVISIBLE (-7075 800);
FORCEPROP 2 LAST PACK_TYPE C0201
J 2
(-7175 800);
DISPLAY 0.553191 (-7175 800);
DISPLAY INVISIBLE (-7175 800);
FORCEPROP 1 LAST MATERIAL X6S
J 2
(-6991 829);
DISPLAY 0.574468 (-6991 829);
PAINT GREEN (-6991 829);
DISPLAY INVISIBLE (-6991 829);
FORCEPROP 2 LAST VOLTAGE 6.3V
J 2
(-7350 800);
DISPLAY 0.553191 (-7350 800);
DISPLAY INVISIBLE (-7350 800);
FORCEPROP 1 LAST PIN_NAMES_ROTATE TRUE
J 2
(-7000 750);
DISPLAY 0.489362 (-7000 750);
PAINT GREEN (-7000 750);
DISPLAY INVISIBLE (-7000 750);
FORCEPROP 2 LAST CDS_LIB pure_quanta
J 2
(-7000 750);
DISPLAY INVISIBLE (-7000 750);
FORCEPROP 1 LAST CDS_LMAN_SYM_OUTLINE -25,50,25,-50
J 2
(-7000 750);
DISPLAY 0.468085 (-7000 750);
PAINT GREEN (-7000 750);
DISPLAY INVISIBLE (-7000 750);
FORCEPROP 1 LAST PATH I84
J 2
(-7000 750);
DISPLAY 0.723404 (-7000 750);
DISPLAY INVISIBLE (-7000 750);
FORCEPROP 1 LAST PART_NUMBER SP_CH4221MEE01
J 2
(-7116 838);
DISPLAY 0.574468 (-7116 838);
PAINT GREEN (-7116 838);
DISPLAY INVISIBLE (-7116 838);
FORCEPROP 1 LAST LOCATION C6692
J 0
(-6750 825);
DISPLAY 1.021277 (-6750 825);
DISPLAY INVISIBLE (-6750 825);
FORCEADD Q_CAP_DIFFBUS..2
R 2
(-7000 800);
FORCEPROP 1 LAST LOCATION C6691
J 2
(-6725 800);
DISPLAY 0.723404 (-6725 800);
PAINT GREEN (-6725 800);
FORCEPROP 2 LAST $SEC 1
J 2
(-6825 875);
DISPLAY 0.680851 (-6825 875);
PAINT MONO (-6825 875);
DISPLAY INVISIBLE (-6825 875);
FORCEPROP 2 LAST CDS_SEC 1
J 2
(-6825 875);
DISPLAY 0.680851 (-6825 875);
DISPLAY INVISIBLE (-6825 875);
FORCEPROP 2 LASTPIN (-6925 800) $PN 1
J 0
(-6915 810);
DISPLAY 0.808511 (-6915 810);
FORCEPROP 2 LASTPIN (-7075 800) $PN 2
J 2
(-7085 810);
DISPLAY 0.808511 (-7085 810);
FORCEPROP 2 LAST VALUE DIFF BUS_0.22UF
J 2
(-7150 800);
DISPLAY 0.553191 (-7150 800);
FORCEPROP 2 LAST TOLERANCE 20%
J 2
(-7075 850);
DISPLAY 0.553191 (-7075 850);
DISPLAY INVISIBLE (-7075 850);
FORCEPROP 2 LAST PACK_TYPE C0201
J 2
(-7175 850);
DISPLAY 0.553191 (-7175 850);
DISPLAY INVISIBLE (-7175 850);
FORCEPROP 1 LAST MATERIAL X6S
J 2
(-6991 879);
DISPLAY 0.574468 (-6991 879);
PAINT GREEN (-6991 879);
DISPLAY INVISIBLE (-6991 879);
FORCEPROP 2 LAST VOLTAGE 6.3V
J 2
(-7350 850);
DISPLAY 0.553191 (-7350 850);
DISPLAY INVISIBLE (-7350 850);
FORCEPROP 1 LAST PIN_NAMES_ROTATE TRUE
J 2
(-7000 800);
DISPLAY 0.489362 (-7000 800);
PAINT GREEN (-7000 800);
DISPLAY INVISIBLE (-7000 800);
FORCEPROP 2 LAST CDS_LIB pure_quanta
J 2
(-7000 800);
DISPLAY INVISIBLE (-7000 800);
FORCEPROP 1 LAST CDS_LMAN_SYM_OUTLINE -25,50,25,-50
J 2
(-7000 800);
DISPLAY 0.468085 (-7000 800);
PAINT GREEN (-7000 800);
DISPLAY INVISIBLE (-7000 800);
FORCEPROP 1 LAST PATH I85
J 2
(-7000 800);
DISPLAY 0.723404 (-7000 800);
DISPLAY INVISIBLE (-7000 800);
FORCEPROP 1 LAST PART_NUMBER SP_CH4221MEE01
J 2
(-7116 888);
DISPLAY 0.574468 (-7116 888);
PAINT GREEN (-7116 888);
DISPLAY INVISIBLE (-7116 888);
FORCEPROP 1 LAST LOCATION C6691
J 0
(-6750 875);
DISPLAY 1.021277 (-6750 875);
DISPLAY INVISIBLE (-6750 875);
FORCEADD Q_CAP_DIFFBUS..2
R 2
(-7000 950);
FORCEPROP 1 LAST LOCATION C6690
J 2
(-6725 950);
DISPLAY 0.723404 (-6725 950);
PAINT GREEN (-6725 950);
FORCEPROP 2 LAST $SEC 1
J 2
(-6825 1025);
DISPLAY 0.680851 (-6825 1025);
PAINT MONO (-6825 1025);
DISPLAY INVISIBLE (-6825 1025);
FORCEPROP 2 LAST CDS_SEC 1
J 2
(-6825 1025);
DISPLAY 0.680851 (-6825 1025);
DISPLAY INVISIBLE (-6825 1025);
FORCEPROP 2 LASTPIN (-6925 950) $PN 1
J 0
(-6915 960);
DISPLAY 0.808511 (-6915 960);
FORCEPROP 2 LASTPIN (-7075 950) $PN 2
J 2
(-7085 960);
DISPLAY 0.808511 (-7085 960);
FORCEPROP 2 LAST VALUE DIFF BUS_0.22UF
J 2
(-7150 950);
DISPLAY 0.553191 (-7150 950);
FORCEPROP 2 LAST TOLERANCE 20%
J 2
(-7075 1000);
DISPLAY 0.553191 (-7075 1000);
DISPLAY INVISIBLE (-7075 1000);
FORCEPROP 2 LAST PACK_TYPE C0201
J 2
(-7175 1000);
DISPLAY 0.553191 (-7175 1000);
DISPLAY INVISIBLE (-7175 1000);
FORCEPROP 1 LAST MATERIAL X6S
J 2
(-6991 1029);
DISPLAY 0.574468 (-6991 1029);
PAINT GREEN (-6991 1029);
DISPLAY INVISIBLE (-6991 1029);
FORCEPROP 2 LAST VOLTAGE 6.3V
J 2
(-7350 1000);
DISPLAY 0.553191 (-7350 1000);
DISPLAY INVISIBLE (-7350 1000);
FORCEPROP 1 LAST PIN_NAMES_ROTATE TRUE
J 2
(-7000 950);
DISPLAY 0.489362 (-7000 950);
PAINT GREEN (-7000 950);
DISPLAY INVISIBLE (-7000 950);
FORCEPROP 2 LAST CDS_LIB pure_quanta
J 2
(-7000 950);
DISPLAY INVISIBLE (-7000 950);
FORCEPROP 1 LAST CDS_LMAN_SYM_OUTLINE -25,50,25,-50
J 2
(-7000 950);
DISPLAY 0.468085 (-7000 950);
PAINT GREEN (-7000 950);
DISPLAY INVISIBLE (-7000 950);
FORCEPROP 1 LAST PATH I86
J 2
(-7000 950);
DISPLAY 0.723404 (-7000 950);
DISPLAY INVISIBLE (-7000 950);
FORCEPROP 1 LAST PART_NUMBER SP_CH4221MEE01
J 2
(-7116 1038);
DISPLAY 0.574468 (-7116 1038);
PAINT GREEN (-7116 1038);
DISPLAY INVISIBLE (-7116 1038);
FORCEPROP 1 LAST LOCATION C6690
J 0
(-6750 1025);
DISPLAY 1.021277 (-6750 1025);
DISPLAY INVISIBLE (-6750 1025);
FORCEADD Q_CAP_DIFFBUS..2
R 2
(-7000 1000);
FORCEPROP 1 LAST LOCATION C6689
J 2
(-6725 1000);
DISPLAY 0.723404 (-6725 1000);
PAINT GREEN (-6725 1000);
FORCEPROP 2 LAST $SEC 1
J 2
(-6825 1075);
DISPLAY 0.680851 (-6825 1075);
PAINT MONO (-6825 1075);
DISPLAY INVISIBLE (-6825 1075);
FORCEPROP 2 LAST CDS_SEC 1
J 2
(-6825 1075);
DISPLAY 0.680851 (-6825 1075);
DISPLAY INVISIBLE (-6825 1075);
FORCEPROP 2 LASTPIN (-6925 1000) $PN 1
J 0
(-6915 1010);
DISPLAY 0.808511 (-6915 1010);
FORCEPROP 2 LASTPIN (-7075 1000) $PN 2
J 2
(-7085 1010);
DISPLAY 0.808511 (-7085 1010);
FORCEPROP 2 LAST VALUE DIFF BUS_0.22UF
J 2
(-7150 1000);
DISPLAY 0.553191 (-7150 1000);
FORCEPROP 2 LAST TOLERANCE 20%
J 2
(-7075 1050);
DISPLAY 0.553191 (-7075 1050);
DISPLAY INVISIBLE (-7075 1050);
FORCEPROP 2 LAST PACK_TYPE C0201
J 2
(-7175 1050);
DISPLAY 0.553191 (-7175 1050);
DISPLAY INVISIBLE (-7175 1050);
FORCEPROP 1 LAST MATERIAL X6S
J 2
(-6991 1079);
DISPLAY 0.574468 (-6991 1079);
PAINT GREEN (-6991 1079);
DISPLAY INVISIBLE (-6991 1079);
FORCEPROP 2 LAST VOLTAGE 6.3V
J 2
(-7350 1050);
DISPLAY 0.553191 (-7350 1050);
DISPLAY INVISIBLE (-7350 1050);
FORCEPROP 1 LAST PIN_NAMES_ROTATE TRUE
J 2
(-7000 1000);
DISPLAY 0.489362 (-7000 1000);
PAINT GREEN (-7000 1000);
DISPLAY INVISIBLE (-7000 1000);
FORCEPROP 1 LAST CDS_LMAN_SYM_OUTLINE -25,50,25,-50
J 2
(-7000 1000);
DISPLAY 0.468085 (-7000 1000);
PAINT GREEN (-7000 1000);
DISPLAY INVISIBLE (-7000 1000);
FORCEPROP 2 LAST CDS_LIB pure_quanta
J 2
(-7000 1000);
DISPLAY INVISIBLE (-7000 1000);
FORCEPROP 1 LAST PATH I87
J 2
(-7000 1000);
DISPLAY 0.723404 (-7000 1000);
DISPLAY INVISIBLE (-7000 1000);
FORCEPROP 1 LAST PART_NUMBER SP_CH4221MEE01
J 2
(-7116 1088);
DISPLAY 0.574468 (-7116 1088);
PAINT GREEN (-7116 1088);
DISPLAY INVISIBLE (-7116 1088);
FORCEPROP 1 LAST LOCATION C6689
J 0
(-6750 1075);
DISPLAY 1.021277 (-6750 1075);
DISPLAY INVISIBLE (-6750 1075);
FORCEADD Q_CAP_DIFFBUS..2
R 2
(-7000 1150);
FORCEPROP 1 LAST LOCATION C6688
J 2
(-6725 1150);
DISPLAY 0.723404 (-6725 1150);
PAINT GREEN (-6725 1150);
FORCEPROP 2 LAST $SEC 1
J 2
(-6825 1225);
DISPLAY 0.680851 (-6825 1225);
PAINT MONO (-6825 1225);
DISPLAY INVISIBLE (-6825 1225);
FORCEPROP 2 LAST CDS_SEC 1
J 2
(-6825 1225);
DISPLAY 0.680851 (-6825 1225);
DISPLAY INVISIBLE (-6825 1225);
FORCEPROP 2 LASTPIN (-6925 1150) $PN 1
J 0
(-6915 1160);
DISPLAY 0.808511 (-6915 1160);
FORCEPROP 2 LASTPIN (-7075 1150) $PN 2
J 2
(-7085 1160);
DISPLAY 0.808511 (-7085 1160);
FORCEPROP 2 LAST VALUE DIFF BUS_0.22UF
J 2
(-7150 1150);
DISPLAY 0.553191 (-7150 1150);
FORCEPROP 2 LAST TOLERANCE 20%
J 2
(-7075 1200);
DISPLAY 0.553191 (-7075 1200);
DISPLAY INVISIBLE (-7075 1200);
FORCEPROP 2 LAST PACK_TYPE C0201
J 2
(-7175 1200);
DISPLAY 0.553191 (-7175 1200);
DISPLAY INVISIBLE (-7175 1200);
FORCEPROP 1 LAST MATERIAL X6S
J 2
(-6991 1229);
DISPLAY 0.574468 (-6991 1229);
PAINT GREEN (-6991 1229);
DISPLAY INVISIBLE (-6991 1229);
FORCEPROP 2 LAST VOLTAGE 6.3V
J 2
(-7350 1200);
DISPLAY 0.553191 (-7350 1200);
DISPLAY INVISIBLE (-7350 1200);
FORCEPROP 1 LAST PIN_NAMES_ROTATE TRUE
J 2
(-7000 1150);
DISPLAY 0.489362 (-7000 1150);
PAINT GREEN (-7000 1150);
DISPLAY INVISIBLE (-7000 1150);
FORCEPROP 2 LAST CDS_LIB pure_quanta
J 2
(-7000 1150);
DISPLAY INVISIBLE (-7000 1150);
FORCEPROP 1 LAST CDS_LMAN_SYM_OUTLINE -25,50,25,-50
J 2
(-7000 1150);
DISPLAY 0.468085 (-7000 1150);
PAINT GREEN (-7000 1150);
DISPLAY INVISIBLE (-7000 1150);
FORCEPROP 1 LAST PATH I88
J 2
(-7000 1150);
DISPLAY 0.723404 (-7000 1150);
DISPLAY INVISIBLE (-7000 1150);
FORCEPROP 1 LAST PART_NUMBER SP_CH4221MEE01
J 2
(-7116 1238);
DISPLAY 0.574468 (-7116 1238);
PAINT GREEN (-7116 1238);
DISPLAY INVISIBLE (-7116 1238);
FORCEPROP 1 LAST LOCATION C6688
J 0
(-6750 1225);
DISPLAY 1.021277 (-6750 1225);
DISPLAY INVISIBLE (-6750 1225);
FORCEADD Q_CAP_DIFFBUS..2
R 2
(-7000 1200);
FORCEPROP 1 LAST LOCATION C6687
J 2
(-6725 1200);
DISPLAY 0.723404 (-6725 1200);
PAINT GREEN (-6725 1200);
FORCEPROP 2 LAST $SEC 1
J 2
(-6825 1275);
DISPLAY 0.680851 (-6825 1275);
PAINT MONO (-6825 1275);
DISPLAY INVISIBLE (-6825 1275);
FORCEPROP 2 LAST CDS_SEC 1
J 2
(-6825 1275);
DISPLAY 0.680851 (-6825 1275);
DISPLAY INVISIBLE (-6825 1275);
FORCEPROP 2 LASTPIN (-6925 1200) $PN 1
J 0
(-6915 1210);
DISPLAY 0.808511 (-6915 1210);
FORCEPROP 2 LASTPIN (-7075 1200) $PN 2
J 2
(-7085 1210);
DISPLAY 0.808511 (-7085 1210);
FORCEPROP 2 LAST VALUE DIFF BUS_0.22UF
J 2
(-7150 1200);
DISPLAY 0.553191 (-7150 1200);
FORCEPROP 2 LAST TOLERANCE 20%
J 2
(-7075 1250);
DISPLAY 0.553191 (-7075 1250);
DISPLAY INVISIBLE (-7075 1250);
FORCEPROP 2 LAST PACK_TYPE C0201
J 2
(-7175 1250);
DISPLAY 0.553191 (-7175 1250);
DISPLAY INVISIBLE (-7175 1250);
FORCEPROP 1 LAST MATERIAL X6S
J 2
(-6991 1279);
DISPLAY 0.574468 (-6991 1279);
PAINT GREEN (-6991 1279);
DISPLAY INVISIBLE (-6991 1279);
FORCEPROP 2 LAST VOLTAGE 6.3V
J 2
(-7350 1250);
DISPLAY 0.553191 (-7350 1250);
DISPLAY INVISIBLE (-7350 1250);
FORCEPROP 1 LAST PIN_NAMES_ROTATE TRUE
J 2
(-7000 1200);
DISPLAY 0.489362 (-7000 1200);
PAINT GREEN (-7000 1200);
DISPLAY INVISIBLE (-7000 1200);
FORCEPROP 2 LAST CDS_LIB pure_quanta
J 2
(-7000 1200);
DISPLAY INVISIBLE (-7000 1200);
FORCEPROP 1 LAST CDS_LMAN_SYM_OUTLINE -25,50,25,-50
J 2
(-7000 1200);
DISPLAY 0.468085 (-7000 1200);
PAINT GREEN (-7000 1200);
DISPLAY INVISIBLE (-7000 1200);
FORCEPROP 1 LAST PATH I89
J 2
(-7000 1200);
DISPLAY 0.723404 (-7000 1200);
DISPLAY INVISIBLE (-7000 1200);
FORCEPROP 1 LAST PART_NUMBER SP_CH4221MEE01
J 2
(-7116 1288);
DISPLAY 0.574468 (-7116 1288);
PAINT GREEN (-7116 1288);
DISPLAY INVISIBLE (-7116 1288);
FORCEPROP 1 LAST LOCATION C6687
J 0
(-6750 1275);
DISPLAY 1.021277 (-6750 1275);
DISPLAY INVISIBLE (-6750 1275);
FORCEADD TAP..1
R 2
(-3350 1550);
FORCEPROP 3 LASTPIN (-3300 1550) SIG_NAME P5E_CPU1_P1_TX_BUF_DN<3>
J 0
(-3290 1560);
DISPLAY 0.659574 (-3290 1560);
PAINT MONO (-3290 1560);
DISPLAY INVISIBLE (-3290 1560);
FORCEPROP 1 LASTPIN (-3300 1550) BN 3
J 2
(-3288 1558);
DISPLAY 0.680851 (-3288 1558);
PAINT GREEN (-3288 1558);
FORCEPROP 2 LAST CDS_LIB standard
J 0
(-3350 1550);
DISPLAY INVISIBLE (-3350 1550);
FORCEPROP 1 LAST BODY_TYPE PLUMBING
J 2
(-3350 1600);
DISPLAY 0.872340 (-3350 1600);
PAINT GREEN (-3350 1600);
DISPLAY INVISIBLE (-3350 1600);
FORCEPROP 1 LAST HDL_TAP TRUE
J 2
(-3675 1425);
DISPLAY 0.872340 (-3675 1425);
DISPLAY INVISIBLE (-3675 1425);
FORCEPROP 1 LAST PATH I9
J 2
(-3348 1550);
DISPLAY 0.872340 (-3348 1550);
PAINT GREEN (-3348 1550);
DISPLAY INVISIBLE (-3348 1550);
FORCEADD TAP..1
R 2
(-7725 1200);
FORCEPROP 3 LASTPIN (-7675 1200) SIG_NAME P5E_CPU1_P1_TX_BUF_DP<13>
J 0
(-7665 1210);
DISPLAY 0.659574 (-7665 1210);
PAINT MONO (-7665 1210);
DISPLAY INVISIBLE (-7665 1210);
FORCEPROP 1 LASTPIN (-7675 1200) BN 13
J 2
(-7663 1208);
DISPLAY 0.680851 (-7663 1208);
PAINT GREEN (-7663 1208);
FORCEPROP 2 LAST CDS_LIB standard
J 0
(-7725 1200);
DISPLAY INVISIBLE (-7725 1200);
FORCEPROP 1 LAST BODY_TYPE PLUMBING
J 2
(-7725 1250);
DISPLAY 0.872340 (-7725 1250);
PAINT GREEN (-7725 1250);
DISPLAY INVISIBLE (-7725 1250);
FORCEPROP 1 LAST HDL_TAP TRUE
J 2
(-8050 1075);
DISPLAY 0.872340 (-8050 1075);
DISPLAY INVISIBLE (-8050 1075);
FORCEPROP 1 LAST PATH I90
J 2
(-7723 1200);
DISPLAY 0.872340 (-7723 1200);
PAINT GREEN (-7723 1200);
DISPLAY INVISIBLE (-7723 1200);
FORCEADD TAP..1
R 2
(-7725 1400);
FORCEPROP 3 LASTPIN (-7675 1400) SIG_NAME P5E_CPU1_P1_TX_BUF_DP<12>
J 0
(-7665 1410);
DISPLAY 0.659574 (-7665 1410);
PAINT MONO (-7665 1410);
DISPLAY INVISIBLE (-7665 1410);
FORCEPROP 1 LASTPIN (-7675 1400) BN 12
J 2
(-7663 1408);
DISPLAY 0.680851 (-7663 1408);
PAINT GREEN (-7663 1408);
FORCEPROP 2 LAST CDS_LIB standard
J 0
(-7725 1400);
DISPLAY INVISIBLE (-7725 1400);
FORCEPROP 1 LAST BODY_TYPE PLUMBING
J 2
(-7725 1450);
DISPLAY 0.872340 (-7725 1450);
PAINT GREEN (-7725 1450);
DISPLAY INVISIBLE (-7725 1450);
FORCEPROP 1 LAST HDL_TAP TRUE
J 2
(-8050 1275);
DISPLAY 0.872340 (-8050 1275);
DISPLAY INVISIBLE (-8050 1275);
FORCEPROP 1 LAST PATH I91
J 2
(-7723 1400);
DISPLAY 0.872340 (-7723 1400);
PAINT GREEN (-7723 1400);
DISPLAY INVISIBLE (-7723 1400);
FORCEADD TAP..1
R 2
(-7725 1600);
FORCEPROP 3 LASTPIN (-7675 1600) SIG_NAME P5E_CPU1_P1_TX_BUF_DP<11>
J 0
(-7665 1610);
DISPLAY 0.659574 (-7665 1610);
PAINT MONO (-7665 1610);
DISPLAY INVISIBLE (-7665 1610);
FORCEPROP 1 LASTPIN (-7675 1600) BN 11
J 2
(-7663 1608);
DISPLAY 0.680851 (-7663 1608);
PAINT GREEN (-7663 1608);
FORCEPROP 2 LAST CDS_LIB standard
J 0
(-7725 1600);
DISPLAY INVISIBLE (-7725 1600);
FORCEPROP 1 LAST BODY_TYPE PLUMBING
J 2
(-7725 1650);
DISPLAY 0.872340 (-7725 1650);
PAINT GREEN (-7725 1650);
DISPLAY INVISIBLE (-7725 1650);
FORCEPROP 1 LAST HDL_TAP TRUE
J 2
(-8050 1475);
DISPLAY 0.872340 (-8050 1475);
DISPLAY INVISIBLE (-8050 1475);
FORCEPROP 1 LAST PATH I92
J 2
(-7723 1600);
DISPLAY 0.872340 (-7723 1600);
PAINT GREEN (-7723 1600);
DISPLAY INVISIBLE (-7723 1600);
FORCEADD TAP..1
R 2
(-7725 1800);
FORCEPROP 3 LASTPIN (-7675 1800) SIG_NAME P5E_CPU1_P1_TX_BUF_DP<10>
J 0
(-7665 1810);
DISPLAY 0.659574 (-7665 1810);
PAINT MONO (-7665 1810);
DISPLAY INVISIBLE (-7665 1810);
FORCEPROP 1 LASTPIN (-7675 1800) BN 10
J 2
(-7663 1808);
DISPLAY 0.680851 (-7663 1808);
PAINT GREEN (-7663 1808);
FORCEPROP 2 LAST CDS_LIB standard
J 0
(-7725 1800);
DISPLAY INVISIBLE (-7725 1800);
FORCEPROP 1 LAST BODY_TYPE PLUMBING
J 2
(-7725 1850);
DISPLAY 0.872340 (-7725 1850);
PAINT GREEN (-7725 1850);
DISPLAY INVISIBLE (-7725 1850);
FORCEPROP 1 LAST HDL_TAP TRUE
J 2
(-8050 1675);
DISPLAY 0.872340 (-8050 1675);
DISPLAY INVISIBLE (-8050 1675);
FORCEPROP 1 LAST PATH I93
J 2
(-7723 1800);
DISPLAY 0.872340 (-7723 1800);
PAINT GREEN (-7723 1800);
DISPLAY INVISIBLE (-7723 1800);
FORCEADD TAP..1
R 2
(-7725 2000);
FORCEPROP 3 LASTPIN (-7675 2000) SIG_NAME P5E_CPU1_P1_TX_BUF_DP<9>
J 0
(-7665 2010);
DISPLAY 0.659574 (-7665 2010);
PAINT MONO (-7665 2010);
DISPLAY INVISIBLE (-7665 2010);
FORCEPROP 1 LASTPIN (-7675 2000) BN 9
J 2
(-7663 2008);
DISPLAY 0.680851 (-7663 2008);
PAINT GREEN (-7663 2008);
FORCEPROP 2 LAST CDS_LIB standard
J 0
(-7725 2000);
DISPLAY INVISIBLE (-7725 2000);
FORCEPROP 1 LAST BODY_TYPE PLUMBING
J 2
(-7725 2050);
DISPLAY 0.872340 (-7725 2050);
PAINT GREEN (-7725 2050);
DISPLAY INVISIBLE (-7725 2050);
FORCEPROP 1 LAST HDL_TAP TRUE
J 2
(-8050 1875);
DISPLAY 0.872340 (-8050 1875);
DISPLAY INVISIBLE (-8050 1875);
FORCEPROP 1 LAST PATH I94
J 2
(-7723 2000);
DISPLAY 0.872340 (-7723 2000);
PAINT GREEN (-7723 2000);
DISPLAY INVISIBLE (-7723 2000);
FORCEADD Q_CAP_DIFFBUS..2
R 2
(-7000 1350);
FORCEPROP 1 LAST LOCATION C6686
J 2
(-6725 1350);
DISPLAY 0.723404 (-6725 1350);
PAINT GREEN (-6725 1350);
FORCEPROP 2 LAST $SEC 1
J 2
(-6825 1425);
DISPLAY 0.680851 (-6825 1425);
PAINT MONO (-6825 1425);
DISPLAY INVISIBLE (-6825 1425);
FORCEPROP 2 LAST CDS_SEC 1
J 2
(-6825 1425);
DISPLAY 0.680851 (-6825 1425);
DISPLAY INVISIBLE (-6825 1425);
FORCEPROP 2 LASTPIN (-6925 1350) $PN 1
J 0
(-6915 1360);
DISPLAY 0.808511 (-6915 1360);
FORCEPROP 2 LASTPIN (-7075 1350) $PN 2
J 2
(-7085 1360);
DISPLAY 0.808511 (-7085 1360);
FORCEPROP 2 LAST VALUE DIFF BUS_0.22UF
J 2
(-7150 1350);
DISPLAY 0.553191 (-7150 1350);
FORCEPROP 2 LAST TOLERANCE 20%
J 2
(-7075 1400);
DISPLAY 0.553191 (-7075 1400);
DISPLAY INVISIBLE (-7075 1400);
FORCEPROP 2 LAST PACK_TYPE C0201
J 2
(-7175 1400);
DISPLAY 0.553191 (-7175 1400);
DISPLAY INVISIBLE (-7175 1400);
FORCEPROP 1 LAST MATERIAL X6S
J 2
(-6991 1429);
DISPLAY 0.574468 (-6991 1429);
PAINT GREEN (-6991 1429);
DISPLAY INVISIBLE (-6991 1429);
FORCEPROP 2 LAST VOLTAGE 6.3V
J 2
(-7350 1400);
DISPLAY 0.553191 (-7350 1400);
DISPLAY INVISIBLE (-7350 1400);
FORCEPROP 1 LAST PIN_NAMES_ROTATE TRUE
J 2
(-7000 1350);
DISPLAY 0.489362 (-7000 1350);
PAINT GREEN (-7000 1350);
DISPLAY INVISIBLE (-7000 1350);
FORCEPROP 1 LAST CDS_LMAN_SYM_OUTLINE -25,50,25,-50
J 2
(-7000 1350);
DISPLAY 0.468085 (-7000 1350);
PAINT GREEN (-7000 1350);
DISPLAY INVISIBLE (-7000 1350);
FORCEPROP 2 LAST CDS_LIB pure_quanta
J 2
(-7000 1350);
DISPLAY INVISIBLE (-7000 1350);
FORCEPROP 1 LAST PATH I95
J 2
(-7000 1350);
DISPLAY 0.723404 (-7000 1350);
DISPLAY INVISIBLE (-7000 1350);
FORCEPROP 1 LAST PART_NUMBER SP_CH4221MEE01
J 2
(-7116 1438);
DISPLAY 0.574468 (-7116 1438);
PAINT GREEN (-7116 1438);
DISPLAY INVISIBLE (-7116 1438);
FORCEPROP 1 LAST LOCATION C6686
J 0
(-6750 1425);
DISPLAY 1.021277 (-6750 1425);
DISPLAY INVISIBLE (-6750 1425);
FORCEADD Q_CAP_DIFFBUS..2
R 2
(-7000 1400);
FORCEPROP 1 LAST LOCATION C6685
J 2
(-6725 1400);
DISPLAY 0.723404 (-6725 1400);
PAINT GREEN (-6725 1400);
FORCEPROP 2 LAST $SEC 1
J 2
(-6825 1475);
DISPLAY 0.680851 (-6825 1475);
PAINT MONO (-6825 1475);
DISPLAY INVISIBLE (-6825 1475);
FORCEPROP 2 LAST CDS_SEC 1
J 2
(-6825 1475);
DISPLAY 0.680851 (-6825 1475);
DISPLAY INVISIBLE (-6825 1475);
FORCEPROP 2 LASTPIN (-6925 1400) $PN 1
J 0
(-6915 1410);
DISPLAY 0.808511 (-6915 1410);
FORCEPROP 2 LASTPIN (-7075 1400) $PN 2
J 2
(-7085 1410);
DISPLAY 0.808511 (-7085 1410);
FORCEPROP 2 LAST VALUE DIFF BUS_0.22UF
J 2
(-7150 1400);
DISPLAY 0.553191 (-7150 1400);
FORCEPROP 2 LAST TOLERANCE 20%
J 2
(-7075 1450);
DISPLAY 0.553191 (-7075 1450);
DISPLAY INVISIBLE (-7075 1450);
FORCEPROP 2 LAST PACK_TYPE C0201
J 2
(-7175 1450);
DISPLAY 0.553191 (-7175 1450);
DISPLAY INVISIBLE (-7175 1450);
FORCEPROP 1 LAST MATERIAL X6S
J 2
(-6991 1479);
DISPLAY 0.574468 (-6991 1479);
PAINT GREEN (-6991 1479);
DISPLAY INVISIBLE (-6991 1479);
FORCEPROP 2 LAST VOLTAGE 6.3V
J 2
(-7350 1450);
DISPLAY 0.553191 (-7350 1450);
DISPLAY INVISIBLE (-7350 1450);
FORCEPROP 1 LAST PIN_NAMES_ROTATE TRUE
J 2
(-7000 1400);
DISPLAY 0.489362 (-7000 1400);
PAINT GREEN (-7000 1400);
DISPLAY INVISIBLE (-7000 1400);
FORCEPROP 1 LAST CDS_LMAN_SYM_OUTLINE -25,50,25,-50
J 2
(-7000 1400);
DISPLAY 0.468085 (-7000 1400);
PAINT GREEN (-7000 1400);
DISPLAY INVISIBLE (-7000 1400);
FORCEPROP 2 LAST CDS_LIB pure_quanta
J 2
(-7000 1400);
DISPLAY INVISIBLE (-7000 1400);
FORCEPROP 1 LAST PATH I96
J 2
(-7000 1400);
DISPLAY 0.723404 (-7000 1400);
DISPLAY INVISIBLE (-7000 1400);
FORCEPROP 1 LAST PART_NUMBER SP_CH4221MEE01
J 2
(-7116 1488);
DISPLAY 0.574468 (-7116 1488);
PAINT GREEN (-7116 1488);
DISPLAY INVISIBLE (-7116 1488);
FORCEPROP 1 LAST LOCATION C6685
J 0
(-6750 1475);
DISPLAY 1.021277 (-6750 1475);
DISPLAY INVISIBLE (-6750 1475);
FORCEADD Q_CAP_DIFFBUS..2
R 2
(-7000 1550);
FORCEPROP 1 LAST LOCATION C6684
J 2
(-6725 1550);
DISPLAY 0.723404 (-6725 1550);
PAINT GREEN (-6725 1550);
FORCEPROP 2 LAST $SEC 1
J 2
(-6825 1625);
DISPLAY 0.680851 (-6825 1625);
PAINT MONO (-6825 1625);
DISPLAY INVISIBLE (-6825 1625);
FORCEPROP 2 LAST CDS_SEC 1
J 2
(-6825 1625);
DISPLAY 0.680851 (-6825 1625);
DISPLAY INVISIBLE (-6825 1625);
FORCEPROP 2 LASTPIN (-6925 1550) $PN 1
J 0
(-6915 1560);
DISPLAY 0.808511 (-6915 1560);
FORCEPROP 2 LASTPIN (-7075 1550) $PN 2
J 2
(-7085 1560);
DISPLAY 0.808511 (-7085 1560);
FORCEPROP 2 LAST VALUE DIFF BUS_0.22UF
J 2
(-7150 1550);
DISPLAY 0.553191 (-7150 1550);
FORCEPROP 2 LAST TOLERANCE 20%
J 2
(-7075 1600);
DISPLAY 0.553191 (-7075 1600);
DISPLAY INVISIBLE (-7075 1600);
FORCEPROP 2 LAST PACK_TYPE C0201
J 2
(-7175 1600);
DISPLAY 0.553191 (-7175 1600);
DISPLAY INVISIBLE (-7175 1600);
FORCEPROP 1 LAST MATERIAL X6S
J 2
(-6991 1629);
DISPLAY 0.574468 (-6991 1629);
PAINT GREEN (-6991 1629);
DISPLAY INVISIBLE (-6991 1629);
FORCEPROP 2 LAST VOLTAGE 6.3V
J 2
(-7350 1600);
DISPLAY 0.553191 (-7350 1600);
DISPLAY INVISIBLE (-7350 1600);
FORCEPROP 1 LAST PIN_NAMES_ROTATE TRUE
J 2
(-7000 1550);
DISPLAY 0.489362 (-7000 1550);
PAINT GREEN (-7000 1550);
DISPLAY INVISIBLE (-7000 1550);
FORCEPROP 2 LAST CDS_LIB pure_quanta
J 2
(-7000 1550);
DISPLAY INVISIBLE (-7000 1550);
FORCEPROP 1 LAST CDS_LMAN_SYM_OUTLINE -25,50,25,-50
J 2
(-7000 1550);
DISPLAY 0.468085 (-7000 1550);
PAINT GREEN (-7000 1550);
DISPLAY INVISIBLE (-7000 1550);
FORCEPROP 1 LAST PATH I97
J 2
(-7000 1550);
DISPLAY 0.723404 (-7000 1550);
DISPLAY INVISIBLE (-7000 1550);
FORCEPROP 1 LAST PART_NUMBER SP_CH4221MEE01
J 2
(-7116 1638);
DISPLAY 0.574468 (-7116 1638);
PAINT GREEN (-7116 1638);
DISPLAY INVISIBLE (-7116 1638);
FORCEPROP 1 LAST LOCATION C6684
J 0
(-6750 1625);
DISPLAY 1.021277 (-6750 1625);
DISPLAY INVISIBLE (-6750 1625);
FORCEADD Q_CAP_DIFFBUS..2
R 2
(-7000 1600);
FORCEPROP 1 LAST LOCATION C6683
J 2
(-6725 1600);
DISPLAY 0.723404 (-6725 1600);
PAINT GREEN (-6725 1600);
FORCEPROP 2 LAST $SEC 1
J 2
(-6825 1675);
DISPLAY 0.680851 (-6825 1675);
PAINT MONO (-6825 1675);
DISPLAY INVISIBLE (-6825 1675);
FORCEPROP 2 LAST CDS_SEC 1
J 2
(-6825 1675);
DISPLAY 0.680851 (-6825 1675);
DISPLAY INVISIBLE (-6825 1675);
FORCEPROP 2 LASTPIN (-6925 1600) $PN 1
J 0
(-6915 1610);
DISPLAY 0.808511 (-6915 1610);
FORCEPROP 2 LASTPIN (-7075 1600) $PN 2
J 2
(-7085 1610);
DISPLAY 0.808511 (-7085 1610);
FORCEPROP 2 LAST VALUE DIFF BUS_0.22UF
J 2
(-7150 1600);
DISPLAY 0.553191 (-7150 1600);
FORCEPROP 2 LAST TOLERANCE 20%
J 2
(-7075 1650);
DISPLAY 0.553191 (-7075 1650);
DISPLAY INVISIBLE (-7075 1650);
FORCEPROP 2 LAST PACK_TYPE C0201
J 2
(-7175 1650);
DISPLAY 0.553191 (-7175 1650);
DISPLAY INVISIBLE (-7175 1650);
FORCEPROP 1 LAST MATERIAL X6S
J 2
(-6991 1679);
DISPLAY 0.574468 (-6991 1679);
PAINT GREEN (-6991 1679);
DISPLAY INVISIBLE (-6991 1679);
FORCEPROP 2 LAST VOLTAGE 6.3V
J 2
(-7350 1650);
DISPLAY 0.553191 (-7350 1650);
DISPLAY INVISIBLE (-7350 1650);
FORCEPROP 1 LAST PIN_NAMES_ROTATE TRUE
J 2
(-7000 1600);
DISPLAY 0.489362 (-7000 1600);
PAINT GREEN (-7000 1600);
DISPLAY INVISIBLE (-7000 1600);
FORCEPROP 2 LAST CDS_LIB pure_quanta
J 2
(-7000 1600);
DISPLAY INVISIBLE (-7000 1600);
FORCEPROP 1 LAST CDS_LMAN_SYM_OUTLINE -25,50,25,-50
J 2
(-7000 1600);
DISPLAY 0.468085 (-7000 1600);
PAINT GREEN (-7000 1600);
DISPLAY INVISIBLE (-7000 1600);
FORCEPROP 1 LAST PATH I98
J 2
(-7000 1600);
DISPLAY 0.723404 (-7000 1600);
DISPLAY INVISIBLE (-7000 1600);
FORCEPROP 1 LAST PART_NUMBER SP_CH4221MEE01
J 2
(-7116 1688);
DISPLAY 0.574468 (-7116 1688);
PAINT GREEN (-7116 1688);
DISPLAY INVISIBLE (-7116 1688);
FORCEPROP 1 LAST LOCATION C6683
J 0
(-6750 1675);
DISPLAY 1.021277 (-6750 1675);
DISPLAY INVISIBLE (-6750 1675);
FORCEADD Q_CAP_DIFFBUS..2
R 2
(-7000 1800);
FORCEPROP 1 LAST LOCATION C6681
J 2
(-6725 1800);
DISPLAY 0.723404 (-6725 1800);
PAINT GREEN (-6725 1800);
FORCEPROP 2 LAST $SEC 1
J 2
(-6825 1875);
DISPLAY 0.680851 (-6825 1875);
PAINT MONO (-6825 1875);
DISPLAY INVISIBLE (-6825 1875);
FORCEPROP 2 LAST CDS_SEC 1
J 2
(-6825 1875);
DISPLAY 0.680851 (-6825 1875);
DISPLAY INVISIBLE (-6825 1875);
FORCEPROP 2 LASTPIN (-6925 1800) $PN 1
J 0
(-6915 1810);
DISPLAY 0.808511 (-6915 1810);
FORCEPROP 2 LASTPIN (-7075 1800) $PN 2
J 2
(-7085 1810);
DISPLAY 0.808511 (-7085 1810);
FORCEPROP 2 LAST VALUE DIFF BUS_0.22UF
J 2
(-7150 1800);
DISPLAY 0.553191 (-7150 1800);
FORCEPROP 2 LAST TOLERANCE 20%
J 2
(-7075 1850);
DISPLAY 0.553191 (-7075 1850);
DISPLAY INVISIBLE (-7075 1850);
FORCEPROP 2 LAST PACK_TYPE C0201
J 2
(-7175 1850);
DISPLAY 0.553191 (-7175 1850);
DISPLAY INVISIBLE (-7175 1850);
FORCEPROP 1 LAST MATERIAL X6S
J 2
(-6991 1879);
DISPLAY 0.574468 (-6991 1879);
PAINT GREEN (-6991 1879);
DISPLAY INVISIBLE (-6991 1879);
FORCEPROP 2 LAST VOLTAGE 6.3V
J 2
(-7350 1850);
DISPLAY 0.553191 (-7350 1850);
DISPLAY INVISIBLE (-7350 1850);
FORCEPROP 1 LAST PIN_NAMES_ROTATE TRUE
J 2
(-7000 1800);
DISPLAY 0.489362 (-7000 1800);
PAINT GREEN (-7000 1800);
DISPLAY INVISIBLE (-7000 1800);
FORCEPROP 2 LAST CDS_LIB pure_quanta
J 2
(-7000 1800);
DISPLAY INVISIBLE (-7000 1800);
FORCEPROP 1 LAST CDS_LMAN_SYM_OUTLINE -25,50,25,-50
J 2
(-7000 1800);
DISPLAY 0.468085 (-7000 1800);
PAINT GREEN (-7000 1800);
DISPLAY INVISIBLE (-7000 1800);
FORCEPROP 1 LAST PATH I99
J 2
(-7000 1800);
DISPLAY 0.723404 (-7000 1800);
DISPLAY INVISIBLE (-7000 1800);
FORCEPROP 1 LAST PART_NUMBER SP_CH4221MEE01
J 2
(-7116 1888);
DISPLAY 0.574468 (-7116 1888);
PAINT GREEN (-7116 1888);
DISPLAY INVISIBLE (-7116 1888);
FORCEPROP 1 LAST LOCATION C6681
J 0
(-6750 1875);
DISPLAY 1.021277 (-6750 1875);
DISPLAY INVISIBLE (-6750 1875);
FORCEADD QUANTA_TITLE_BLOCK_C..1
(0 0);
FORCEPROP 0 LAST CDS_CON_LAST_MODIFIED Thu Sep 14 16:12:50 2023
J 0
(-1885 15);
DISPLAY INVISIBLE (-1885 15);
FORCEPROP 1 LAST CUSTOM_TXT_CDS <CON_LAST_MODIFIED>
J 0
(-1885 15);
DISPLAY 0.978723 (-1885 15);
FORCEPROP 2 LAST CUSTOM_TXT_CDS <XR_PAGE_TITLE>
J 0
(-7890 5250);
DISPLAY 0.638298 (-7890 5250);
PAINT PINK (-7890 5250);
DISPLAY INVISIBLE (-7890 5250);
FORCEPROP 1 LAST CUSTOM_TXT_CDS <NAME_2>
J 0
(-3175 50);
FORCEPROP 1 LAST CUSTOM_TXT_CDS <NAME_1>
J 0
(-3175 175);
FORCEPROP 1 LAST CUSTOM_TXT_CDS <Q_NUMBER>
J 0
(-1403 103);
DISPLAY 1.212766 (-1403 103);
FORCEPROP 1 LAST CUSTOM_TXT_CDS <Q_PROJ>
J 0
(-2382 102);
DISPLAY 1.212766 (-2382 102);
FORCEPROP 1 LAST CUSTOM_TXT_CDS <Q_REV>
J 0
(-184 103);
DISPLAY 1.212766 (-184 103);
FORCEPROP 1 LAST CUSTOM_TXT_CDS <CON_PAGE_NUM> OF <CON_TOTAL_PAGES>
J 0
(-446 18);
DISPLAY 0.978723 (-446 18);
FORCEPROP 1 LAST Q_TITLE RETIMER_CPU1_P1(4)
J 0
(-9366 26);
DISPLAY 2.446809 (-9366 26);
PAINT GREEN (-9366 26);
FORCEPROP 2 LAST PAGE_BORDER TRUE
J 0
(-7890 5250);
DISPLAY 0.638298 (-7890 5250);
PAINT PINK (-7890 5250);
DISPLAY INVISIBLE (-7890 5250);
FORCEPROP 2 LAST CDS_LIB pure_quanta
J 0
(0 0);
DISPLAY INVISIBLE (0 0);
FORCEPROP 1 LAST CDS_LMAN_SYM_OUTLINE -9475,6775,100,-125
J 0
(0 0);
DISPLAY 0.468085 (0 0);
PAINT GREEN (0 0);
DISPLAY INVISIBLE (0 0);
FORCEPROP 2 LAST CDS_XR_PAGE_TITLE CR-331 : @T6G_MB_LIB.T6G(SCH_1):PAGE331
J 0
(-7890 5250);
DISPLAY 0.638298 (-7890 5250);
PAINT PINK (-7890 5250);
DISPLAY INVISIBLE (-7890 5250);
FORCEPROP 1 LAST Q_DEPT BU9
J 1
(-3763 49);
DISPLAY 1.957447 (-3763 49);
PAINT GREEN (-3763 49);
DISPLAY INVISIBLE (-3763 49);
FORCEPROP 1 LAST COMMENT_BODY TRUE
J 0
(12 -13);
DISPLAY 0.978723 (12 -13);
PAINT GREEN (12 -13);
DISPLAY INVISIBLE (12 -13);
WIRE 17 -1 (-3150 2225)(-3150 2025);
WIRE 17 -1 (-4250 2225)(-3150 2225);
FORCEPROP 2 LAST SIG_NAME P5E_CPU1_P1_TX_BUF_DP<7:0>
J 0
(-4235 2235);
DISPLAY 0.680851 (-4235 2235);
PAINT WHITE (-4235 2235);
WIRE 17 -1 (-1775 1825)(-1775 1625);
WIRE 17 -1 (-1775 2025)(-1775 1825);
WIRE 17 -1 (-1775 1425)(-1775 1625);
WIRE 17 -1 (-1775 1425)(-1775 1225);
WIRE 17 -1 (-1775 2225)(-1775 2025);
WIRE 17 -1 (-1775 2225)(-675 2225);
FORCEPROP 2 LAST SIG_NAME P5E_CPU1_P1_TX_BUF_C_DP<7:0>
J 0
(-1585 2235);
DISPLAY 0.680851 (-1585 2235);
PAINT WHITE (-1585 2235);
WIRE 17 -1 (-3400 775)(-3400 975);
WIRE 17 -1 (-3400 975)(-3400 1175);
WIRE 17 -1 (-3400 1175)(-3400 1375);
WIRE 17 -1 (-3400 1375)(-3400 1575);
WIRE 17 -1 (-3400 1575)(-3400 1775);
WIRE 17 -1 (-3400 1775)(-3400 1975);
WIRE 17 -1 (-3400 1975)(-3400 2175);
WIRE 17 -1 (-4250 2175)(-3400 2175);
FORCEPROP 2 LAST SIG_NAME P5E_CPU1_P1_TX_BUF_DN<7:0>
J 0
(-4235 2185);
DISPLAY 0.680851 (-4235 2185);
PAINT WHITE (-4235 2185);
WIRE 17 -1 (-3150 1025)(-3150 825);
WIRE 17 -1 (-3150 1225)(-3150 1025);
WIRE 17 -1 (-3150 1425)(-3150 1225);
WIRE 17 -1 (-3150 1425)(-3150 1625);
WIRE 17 -1 (-3150 1825)(-3150 1625);
WIRE 17 -1 (-3150 2025)(-3150 1825);
WIRE 17 -1 (-1775 1025)(-1775 825);
WIRE 17 -1 (-1775 1225)(-1775 1025);
WIRE 17 -1 (-1575 975)(-1575 775);
WIRE 17 -1 (-1575 1175)(-1575 975);
WIRE 17 -1 (-1575 1375)(-1575 1175);
WIRE 17 -1 (-1575 1375)(-1575 1575);
WIRE 17 -1 (-1575 1775)(-1575 1575);
WIRE 17 -1 (-1575 1975)(-1575 1775);
WIRE 17 -1 (-1575 2175)(-1575 1975);
FORCEPROP 2 LAST SIG_NAME P5E_CPU1_P1_TX_BUF_C_DN<7:0>
J 0
(-1585 2185);
DISPLAY 0.680851 (-1585 2185);
PAINT WHITE (-1585 2185);
WIRE 17 -1 (-8025 775)(-8025 975);
WIRE 17 -1 (-8025 975)(-8025 1175);
WIRE 17 -1 (-8025 1175)(-8025 1375);
WIRE 17 -1 (-8025 1375)(-8025 1575);
WIRE 17 -1 (-8025 1575)(-8025 1775);
WIRE 17 -1 (-8025 1775)(-8025 1975);
WIRE 17 -1 (-8025 1975)(-8025 2175);
WIRE 17 -1 (-8875 2175)(-8025 2175);
FORCEPROP 2 LAST SIG_NAME P5E_CPU1_P1_TX_BUF_DN<15:8>
J 0
(-8860 2185);
DISPLAY 0.680851 (-8860 2185);
PAINT WHITE (-8860 2185);
WIRE 17 -1 (-7775 1025)(-7775 825);
WIRE 17 -1 (-7775 1225)(-7775 1025);
WIRE 17 -1 (-7775 1425)(-7775 1225);
WIRE 17 -1 (-7775 1425)(-7775 1625);
WIRE 17 -1 (-7775 1825)(-7775 1625);
WIRE 17 -1 (-7775 2025)(-7775 1825);
WIRE 17 -1 (-7775 2225)(-7775 2025);
WIRE 17 -1 (-8875 2225)(-7775 2225);
FORCEPROP 2 LAST SIG_NAME P5E_CPU1_P1_TX_BUF_DP<15:8>
J 0
(-8860 2235);
DISPLAY 0.680851 (-8860 2235);
PAINT WHITE (-8860 2235);
WIRE 17 -1 (-6200 975)(-6200 775);
WIRE 17 -1 (-6200 1175)(-6200 975);
WIRE 17 -1 (-6200 1375)(-6200 1175);
WIRE 17 -1 (-6200 1375)(-6200 1575);
WIRE 17 -1 (-6200 1775)(-6200 1575);
WIRE 17 -1 (-6200 1975)(-6200 1775);
WIRE 17 -1 (-6200 2175)(-6200 1975);
FORCEPROP 2 LAST SIG_NAME P5E_CPU1_P1_TX_BUF_C_DN<15:8>
J 0
(-6210 2185);
DISPLAY 0.680851 (-6210 2185);
PAINT WHITE (-6210 2185);
WIRE 17 -1 (-6400 1025)(-6400 825);
WIRE 17 -1 (-6400 1225)(-6400 1025);
WIRE 17 -1 (-6400 1425)(-6400 1225);
WIRE 17 -1 (-6400 1425)(-6400 1625);
WIRE 17 -1 (-6400 1825)(-6400 1625);
WIRE 17 -1 (-6400 2025)(-6400 1825);
WIRE 17 -1 (-6400 2225)(-6400 2025);
WIRE 17 -1 (-6400 2225)(-5300 2225);
FORCEPROP 2 LAST SIG_NAME P5E_CPU1_P1_TX_BUF_C_DP<15:8>
J 0
(-6210 2235);
DISPLAY 0.680851 (-6210 2235);
PAINT WHITE (-6210 2235);
WIRE 17 -1 (-6550 5750)(-6550 5400);
WIRE 17 -1 (-6550 5750)(-5675 5750);
FORCEPROP 2 LAST SIG_NAME P5E_CPU1_P1_TX_BUF_DN<15:8>
J 0
(-6560 5760);
DISPLAY 0.680851 (-6560 5760);
PAINT WHITE (-6560 5760);
WIRE 17 -1 (-6550 5400)(-6550 5050);
WIRE 17 -1 (-6550 5050)(-6550 4700);
WIRE 17 -1 (-6550 4350)(-6550 4700);
WIRE 17 -1 (-6750 4100)(-6750 3750);
WIRE 17 -1 (-6750 4450)(-6750 4100);
WIRE 17 -1 (-6750 3750)(-6750 3400);
WIRE 17 -1 (-6750 4450)(-6750 4800);
WIRE 17 -1 (-6750 5150)(-6750 4800);
WIRE 17 -1 (-6750 5500)(-6750 5150);
WIRE 17 -1 (-6750 5850)(-6750 5500);
WIRE 17 -1 (-6750 5850)(-5650 5850);
FORCEPROP 2 LAST SIG_NAME P5E_CPU1_P1_TX_BUF_DP<15:8>
J 0
(-6560 5860);
DISPLAY 0.680851 (-6560 5860);
PAINT WHITE (-6560 5860);
WIRE 17 -1 (-1375 5375)(-1375 5025);
WIRE 17 -1 (-1375 5725)(-1375 5375);
FORCEPROP 2 LAST SIG_NAME P5E_CPU1_P1_TX_BUF_DN<7:0>
J 0
(-1385 5735);
DISPLAY 0.680851 (-1385 5735);
PAINT WHITE (-1385 5735);
WIRE 17 -1 (-1375 4325)(-1375 3975);
WIRE 17 -1 (-1375 4325)(-1375 4675);
WIRE 17 -1 (-1375 3975)(-1375 3625);
WIRE 17 -1 (-1375 3625)(-1375 3275);
WIRE 17 -1 (-1375 5025)(-1375 4675);
WIRE 17 -1 (-1575 3725)(-1575 3375);
WIRE 17 -1 (-1575 4075)(-1575 3725);
WIRE 17 -1 (-1575 4425)(-1575 4075);
WIRE 17 -1 (-1575 4425)(-1575 4775);
WIRE 17 -1 (-1575 5125)(-1575 4775);
WIRE 17 -1 (-1575 5475)(-1575 5125);
WIRE 17 -1 (-1575 5825)(-1575 5475);
WIRE 17 -1 (-1575 5825)(-475 5825);
FORCEPROP 2 LAST SIG_NAME P5E_CPU1_P1_TX_BUF_DP<7:0>
J 0
(-1385 5835);
DISPLAY 0.680851 (-1385 5835);
PAINT WHITE (-1385 5835);
WIRE 17 -1 (-6550 4350)(-6550 4000);
WIRE 17 -1 (-6550 4000)(-6550 3650);
WIRE 17 -1 (-6550 3650)(-6550 3300);
WIRE 17 -1 (-1575 2175)(-675 2175);
WIRE 17 -1 (-6200 2175)(-5300 2175);
WIRE 17 -1 (-1375 5725)(-500 5725);
WIRE 16 -1 (-7075 3625)(-6650 3625);
WIRE 16 -1 (-7075 4075)(-6850 4075);
WIRE 16 -1 (-7075 3375)(-6850 3375);
WIRE 16 -1 (-7075 3275)(-6650 3275);
WIRE 16 -1 (-7075 5725)(-6650 5725);
WIRE 16 -1 (-7075 5475)(-6850 5475);
WIRE 16 -1 (-7075 5125)(-6850 5125);
WIRE 16 -1 (-7075 4675)(-6650 4675);
WIRE 16 -1 (-1900 4050)(-1675 4050);
WIRE 16 -1 (-1900 3600)(-1475 3600);
WIRE 16 -1 (-1900 5450)(-1675 5450);
WIRE 16 -1 (-1900 5350)(-1475 5350);
WIRE 16 -1 (-1900 5800)(-1675 5800);
WIRE 16 -1 (-1900 4650)(-1475 4650);
WIRE 16 -1 (-1900 4750)(-1675 4750);
WIRE 16 -1 (-1900 4300)(-1475 4300);
WIRE 16 -1 (-1900 4400)(-1675 4400);
WIRE 16 -1 (-1900 5100)(-1675 5100);
WIRE 16 -1 (-1900 3700)(-1675 3700);
WIRE 16 -1 (-7075 4775)(-6850 4775);
WIRE 16 -1 (-1900 5700)(-1475 5700);
WIRE 16 -1 (-1900 3250)(-1475 3250);
WIRE 16 -1 (-7075 3975)(-6650 3975);
WIRE 16 -1 (-7075 4325)(-6650 4325);
WIRE 16 -1 (-7075 4425)(-6850 4425);
WIRE 16 -1 (-1900 3350)(-1675 3350);
WIRE 16 -1 (-1900 3950)(-1475 3950);
WIRE 16 -1 (-1900 5000)(-1475 5000);
WIRE 16 -1 (-7075 5825)(-6850 5825);
WIRE 16 -1 (-7075 3725)(-6850 3725);
WIRE 16 -1 (-7075 5025)(-6650 5025);
WIRE 16 -1 (-7075 5375)(-6650 5375);
WIRE 16 -1 (-6925 2150)(-6300 2150);
WIRE 16 -1 (-6925 2200)(-6500 2200);
WIRE 16 -1 (-7075 2200)(-7675 2200);
WIRE 16 -1 (-7075 2150)(-7925 2150);
WIRE 16 -1 (-6925 2000)(-6500 2000);
WIRE 16 -1 (-6925 1950)(-6300 1950);
WIRE 16 -1 (-6925 1800)(-6500 1800);
WIRE 16 -1 (-6925 1750)(-6300 1750);
WIRE 16 -1 (-6925 1600)(-6500 1600);
WIRE 16 -1 (-6925 1550)(-6300 1550);
WIRE 16 -1 (-6925 1400)(-6500 1400);
WIRE 16 -1 (-6925 1350)(-6300 1350);
WIRE 16 -1 (-6925 1200)(-6500 1200);
WIRE 16 -1 (-6925 1150)(-6300 1150);
WIRE 16 -1 (-7075 2000)(-7675 2000);
WIRE 16 -1 (-7075 1800)(-7675 1800);
WIRE 16 -1 (-7075 1600)(-7675 1600);
WIRE 16 -1 (-7075 1400)(-7675 1400);
WIRE 16 -1 (-7075 1200)(-7675 1200);
WIRE 16 -1 (-6925 1000)(-6500 1000);
WIRE 16 -1 (-6925 950)(-6300 950);
WIRE 16 -1 (-6925 800)(-6500 800);
WIRE 16 -1 (-6925 750)(-6300 750);
WIRE 16 -1 (-7075 1000)(-7675 1000);
WIRE 16 -1 (-7075 800)(-7675 800);
WIRE 16 -1 (-7075 1950)(-7925 1950);
WIRE 16 -1 (-7075 1750)(-7925 1750);
WIRE 16 -1 (-7075 1350)(-7925 1350);
WIRE 16 -1 (-7075 1550)(-7925 1550);
WIRE 16 -1 (-7075 1150)(-7925 1150);
WIRE 16 -1 (-7075 950)(-7925 950);
WIRE 16 -1 (-7075 750)(-7925 750);
WIRE 16 -1 (-2300 2200)(-1875 2200);
WIRE 16 -1 (-2300 2150)(-1675 2150);
WIRE 16 -1 (-2300 2000)(-1875 2000);
WIRE 16 -1 (-2300 1950)(-1675 1950);
WIRE 16 -1 (-2300 1750)(-1675 1750);
WIRE 16 -1 (-2300 1800)(-1875 1800);
WIRE 16 -1 (-2300 1550)(-1675 1550);
WIRE 16 -1 (-2300 1400)(-1875 1400);
WIRE 16 -1 (-2300 1350)(-1675 1350);
WIRE 16 -1 (-2300 1150)(-1675 1150);
WIRE 16 -1 (-2300 1200)(-1875 1200);
WIRE 16 -1 (-2300 1000)(-1875 1000);
WIRE 16 -1 (-2300 950)(-1675 950);
WIRE 16 -1 (-2300 750)(-1675 750);
WIRE 16 -1 (-2300 800)(-1875 800);
WIRE 16 -1 (-2450 2200)(-3050 2200);
WIRE 16 -1 (-2450 2150)(-3300 2150);
WIRE 16 -1 (-2450 1800)(-3050 1800);
WIRE 16 -1 (-2450 1950)(-3300 1950);
WIRE 16 -1 (-2450 1600)(-3050 1600);
WIRE 16 -1 (-2450 1200)(-3050 1200);
WIRE 16 -1 (-2450 1400)(-3050 1400);
WIRE 16 -1 (-2450 1000)(-3050 1000);
WIRE 16 -1 (-2450 1750)(-3300 1750);
WIRE 16 -1 (-2450 1550)(-3300 1550);
WIRE 16 -1 (-2450 1350)(-3300 1350);
WIRE 16 -1 (-2450 1150)(-3300 1150);
WIRE 16 -1 (-2450 950)(-3300 950);
WIRE 16 -1 (-2450 800)(-3050 800);
WIRE 16 -1 (-2450 750)(-3300 750);
WIRE 16 -1 (-2300 1600)(-1875 1600);
WIRE 16 -1 (-2450 2000)(-3050 2000);
FORCENOTE
RETIMER TO EXAMAX
(-3425 2900) 0;
DISPLAY LEFT (-3425 2900);
DISPLAY 3.148936 (-3425 2900);
FORCENOTE
P5E_CPU1_P1_TX_BUF_DP/DN<0-15> LANE REVERSAL
(-8975 6450) 0;
DISPLAY LEFT (-8975 6450);
DISPLAY 2.000000 (-8975 6450);
FORCENOTE
RETIMER TO EXAMAX
(-8425 2925) 0;
DISPLAY LEFT (-8425 2925);
DISPLAY 3.148936 (-8425 2925);
QUIT
